FILE_TYPE = MACRO_DRAWING;
SET COLOR_WIRE YELLOW;
SET COLOR_PROP ORANGE;
SET COLOR_DOT WHITE;
SET COLOR_ARC YELLOW;
SET COLOR_BODY GREEN;
SET COLOR_NOTE PURPLE;
SET PROP_DISPLAY VALUE;
SET PAGE_NUMBER P88;
FORCEADD GND..1
(-2250 1950);
FORCEPROP 3 LASTPIN (-2250 2000) SIG_NAME GND\g
J 0
(-2240 2010);
DISPLAY 0.659574 (-2240 2010);
PAINT MONO (-2240 2010);
DISPLAY INVISIBLE (-2240 2010);
FORCEPROP 2 LAST CDS_LIB mstr_symbols
J 0
(-2250 1950);
DISPLAY 0.723404 (-2250 1950);
DISPLAY INVISIBLE (-2250 1950);
FORCEPROP 1 LAST SIZE 1B
J 0
(-2175 1900);
DISPLAY 0.851064 (-2175 1900);
PAINT GREEN (-2175 1900);
DISPLAY INVISIBLE (-2175 1900);
FORCEPROP 1 LAST VOLTAGE 0.0
J 0
(-2295 1907);
DISPLAY 0.723404 (-2295 1907);
PAINT SKYBLUE (-2295 1907);
DISPLAY INVISIBLE (-2295 1907);
FORCEPROP 1 LAST BODY_TYPE PLUMBING
J 0
(-2295 1907);
DISPLAY 0.340426 (-2295 1907);
PAINT GREEN (-2295 1907);
DISPLAY INVISIBLE (-2295 1907);
FORCEPROP 1 LAST HDL_POWER GND
J 0
(-2250 2100);
DISPLAY 0.851064 (-2250 2100);
PAINT GREEN (-2250 2100);
DISPLAY INVISIBLE (-2250 2100);
FORCEPROP 1 LAST PATH I150
J 0
(-2175 1950);
DISPLAY 0.872340 (-2175 1950);
PAINT GREEN (-2175 1950);
DISPLAY INVISIBLE (-2175 1950);
FORCEADD GND..1
(-450 1750);
FORCEPROP 3 LASTPIN (-450 1800) SIG_NAME GND\g
J 0
(-440 1810);
DISPLAY 0.659574 (-440 1810);
PAINT MONO (-440 1810);
DISPLAY INVISIBLE (-440 1810);
FORCEPROP 2 LAST CDS_LIB mstr_symbols
J 0
(-450 1750);
DISPLAY 0.723404 (-450 1750);
DISPLAY INVISIBLE (-450 1750);
FORCEPROP 1 LAST SIZE 1B
J 0
(-375 1700);
DISPLAY 0.851064 (-375 1700);
PAINT GREEN (-375 1700);
DISPLAY INVISIBLE (-375 1700);
FORCEPROP 1 LAST VOLTAGE 0.0
J 0
(-495 1707);
DISPLAY 0.723404 (-495 1707);
PAINT SKYBLUE (-495 1707);
DISPLAY INVISIBLE (-495 1707);
FORCEPROP 1 LAST BODY_TYPE PLUMBING
J 0
(-495 1707);
DISPLAY 0.340426 (-495 1707);
PAINT GREEN (-495 1707);
DISPLAY INVISIBLE (-495 1707);
FORCEPROP 1 LAST HDL_POWER GND
J 0
(-450 1900);
DISPLAY 0.851064 (-450 1900);
PAINT GREEN (-450 1900);
DISPLAY INVISIBLE (-450 1900);
FORCEPROP 1 LAST PATH I152
J 0
(-375 1750);
DISPLAY 0.872340 (-375 1750);
PAINT GREEN (-375 1750);
DISPLAY INVISIBLE (-375 1750);
FORCEADD OFFPAGE..5
(-8375 2100);
FORCEPROP 2 LAST $XR0 13 
J 0
(-8629 2100);
DISPLAY 0.638298 (-8629 2100);
PAINT MONO (-8629 2100);
FORCEPROP 2 LAST CDS_LIB mstr_standard
J 0
(-8375 2100);
DISPLAY 0.808511 (-8375 2100);
DISPLAY INVISIBLE (-8375 2100);
FORCEPROP 1 LAST OFFPAGE TRUE
J 0
(-8050 1975);
DISPLAY 0.872340 (-8050 1975);
PAINT GREEN (-8050 1975);
DISPLAY INVISIBLE (-8050 1975);
FORCEPROP 1 LAST COMMENT_BODY TRUE
J 0
(-8275 2025);
DISPLAY 0.872340 (-8275 2025);
PAINT GREEN (-8275 2025);
DISPLAY INVISIBLE (-8275 2025);
FORCEPROP 2 LAST PATH I167
J 0
(-8325 2175);
DISPLAY 0.808511 (-8325 2175);
DISPLAY INVISIBLE (-8325 2175);
FORCEADD OFFPAGE..5
(-8375 2150);
FORCEPROP 2 LAST $XR0 13 
J 0
(-8629 2150);
DISPLAY 0.638298 (-8629 2150);
PAINT MONO (-8629 2150);
FORCEPROP 2 LAST CDS_LIB mstr_standard
J 0
(-8375 2150);
DISPLAY 0.808511 (-8375 2150);
DISPLAY INVISIBLE (-8375 2150);
FORCEPROP 1 LAST OFFPAGE TRUE
J 0
(-8050 2025);
DISPLAY 0.872340 (-8050 2025);
PAINT GREEN (-8050 2025);
DISPLAY INVISIBLE (-8050 2025);
FORCEPROP 1 LAST COMMENT_BODY TRUE
J 0
(-8275 2075);
DISPLAY 0.872340 (-8275 2075);
PAINT GREEN (-8275 2075);
DISPLAY INVISIBLE (-8275 2075);
FORCEPROP 2 LAST PATH I171
J 0
(-8325 2225);
DISPLAY 0.808511 (-8325 2225);
DISPLAY INVISIBLE (-8325 2225);
FORCEADD OFFPAGE..6
(-8375 3750);
FORCEPROP 2 LAST $XR0 13 
J 0
(-8654 3750);
DISPLAY 0.638298 (-8654 3750);
PAINT MONO (-8654 3750);
FORCEPROP 2 LAST CDS_LIB mstr_standard
J 0
(-8375 3750);
DISPLAY 0.723404 (-8375 3750);
PAINT MONO (-8375 3750);
DISPLAY INVISIBLE (-8375 3750);
FORCEPROP 1 LAST OFFPAGE TRUE
J 0
(-8050 3625);
DISPLAY 0.872340 (-8050 3625);
PAINT GREEN (-8050 3625);
DISPLAY INVISIBLE (-8050 3625);
FORCEPROP 1 LAST COMMENT_BODY TRUE
J 0
(-8275 3675);
DISPLAY 0.872340 (-8275 3675);
PAINT GREEN (-8275 3675);
DISPLAY INVISIBLE (-8275 3675);
FORCEPROP 2 LAST PATH I174
J 0
(-8325 3825);
DISPLAY 0.808511 (-8325 3825);
DISPLAY INVISIBLE (-8325 3825);
FORCEADD VCC_CORE..1
(-8475 3625);
FORCEPROP 3 LASTPIN (-8475 3575) SIG_NAME P3V3_AUX\g
J 0
(-8465 3585);
DISPLAY 0.659574 (-8465 3585);
PAINT MONO (-8465 3585);
DISPLAY INVISIBLE (-8465 3585);
FORCEPROP 1 LAST HDL_POWER P3V3_AUX
J 1
(-8475 3675);
DISPLAY 0.489362 (-8475 3675);
PAINT GREEN (-8475 3675);
FORCEPROP 2 LAST CDS_LIB mstr_symbols
J 0
(-8475 3625);
PAINT MONO (-8475 3625);
DISPLAY INVISIBLE (-8475 3625);
FORCEPROP 0 LAST VOLTAGE 3.3
J 0
(-8750 3775);
DISPLAY 1.021277 (-8750 3775);
PAINT SKYBLUE (-8750 3775);
DISPLAY INVISIBLE (-8750 3775);
FORCEPROP 2 LAST ROOM PVCCINFAON_CPU0_CTRL
J 0
(-8475 3725);
DISPLAY 0.808511 (-8475 3725);
PAINT RED (-8475 3725);
DISPLAY INVISIBLE (-8475 3725);
FORCEPROP 1 LAST PATH I175
J 0
(-8425 3650);
DISPLAY 0.872340 (-8425 3650);
PAINT GREEN (-8425 3650);
DISPLAY INVISIBLE (-8425 3650);
FORCEADD OFFPAGE..1
(-8100 3250);
FORCEPROP 2 LAST $XR0 13 
J 0
(-8321 3250);
DISPLAY 0.638298 (-8321 3250);
PAINT MONO (-8321 3250);
FORCEPROP 2 LAST CDS_LIB mstr_standard
J 0
(-8100 3250);
DISPLAY 0.808511 (-8100 3250);
DISPLAY INVISIBLE (-8100 3250);
FORCEPROP 1 LAST OFFPAGE TRUE
J 0
(-7775 3125);
DISPLAY 0.872340 (-7775 3125);
PAINT GREEN (-7775 3125);
DISPLAY INVISIBLE (-7775 3125);
FORCEPROP 1 LAST COMMENT_BODY TRUE
J 0
(-7975 3150);
DISPLAY 0.872340 (-7975 3150);
PAINT GREEN (-7975 3150);
DISPLAY INVISIBLE (-7975 3150);
FORCEPROP 2 LAST PATH I177
J 0
(-8300 3475);
DISPLAY 0.808511 (-8300 3475);
DISPLAY INVISIBLE (-8300 3475);
FORCEADD OFFPAGE..6
(-8375 4200);
FORCEPROP 2 LAST $XR0 13 
J 0
(-8654 4200);
DISPLAY 0.638298 (-8654 4200);
PAINT MONO (-8654 4200);
FORCEPROP 2 LAST CDS_LIB mstr_standard
J 0
(-8375 4200);
DISPLAY 0.723404 (-8375 4200);
PAINT MONO (-8375 4200);
DISPLAY INVISIBLE (-8375 4200);
FORCEPROP 1 LAST OFFPAGE TRUE
J 0
(-8050 4075);
DISPLAY 0.872340 (-8050 4075);
PAINT GREEN (-8050 4075);
DISPLAY INVISIBLE (-8050 4075);
FORCEPROP 1 LAST COMMENT_BODY TRUE
J 0
(-8275 4125);
DISPLAY 0.872340 (-8275 4125);
PAINT GREEN (-8275 4125);
DISPLAY INVISIBLE (-8275 4125);
FORCEPROP 2 LAST PATH I178
J 0
(-8325 4275);
DISPLAY 0.808511 (-8325 4275);
DISPLAY INVISIBLE (-8325 4275);
FORCEADD OFFPAGE..1
(-8375 4300);
FORCEPROP 2 LAST $XR0 13 
J 0
(-8626 4300);
DISPLAY 0.638298 (-8626 4300);
PAINT MONO (-8626 4300);
FORCEPROP 2 LAST CDS_LIB mstr_standard
J 0
(-8375 4300);
DISPLAY 0.723404 (-8375 4300);
PAINT MONO (-8375 4300);
DISPLAY INVISIBLE (-8375 4300);
FORCEPROP 1 LAST OFFPAGE TRUE
J 0
(-8050 4175);
DISPLAY 0.872340 (-8050 4175);
PAINT GREEN (-8050 4175);
DISPLAY INVISIBLE (-8050 4175);
FORCEPROP 1 LAST COMMENT_BODY TRUE
J 0
(-8250 4200);
DISPLAY 0.872340 (-8250 4200);
PAINT GREEN (-8250 4200);
DISPLAY INVISIBLE (-8250 4200);
FORCEPROP 2 LAST PATH I179
J 0
(-8325 4375);
DISPLAY 0.808511 (-8325 4375);
DISPLAY INVISIBLE (-8325 4375);
FORCEADD OFFPAGE..1
(-8375 4250);
FORCEPROP 2 LAST $XR0 13 
J 0
(-8626 4250);
DISPLAY 0.638298 (-8626 4250);
PAINT MONO (-8626 4250);
FORCEPROP 2 LAST CDS_LIB mstr_standard
J 0
(-8375 4250);
DISPLAY 0.808511 (-8375 4250);
DISPLAY INVISIBLE (-8375 4250);
FORCEPROP 1 LAST OFFPAGE TRUE
J 0
(-8050 4125);
DISPLAY 0.872340 (-8050 4125);
PAINT GREEN (-8050 4125);
DISPLAY INVISIBLE (-8050 4125);
FORCEPROP 1 LAST COMMENT_BODY TRUE
J 0
(-8250 4150);
DISPLAY 0.872340 (-8250 4150);
PAINT GREEN (-8250 4150);
DISPLAY INVISIBLE (-8250 4150);
FORCEPROP 2 LAST PATH I180
J 0
(-8325 4325);
DISPLAY 0.808511 (-8325 4325);
DISPLAY INVISIBLE (-8325 4325);
FORCEADD OFFPAGE..1
(-8375 4400);
FORCEPROP 2 LAST $XR0 13 
J 0
(-8626 4400);
DISPLAY 0.638298 (-8626 4400);
PAINT MONO (-8626 4400);
FORCEPROP 2 LAST CDS_LIB mstr_standard
J 0
(-8375 4400);
DISPLAY 0.808511 (-8375 4400);
DISPLAY INVISIBLE (-8375 4400);
FORCEPROP 1 LAST OFFPAGE TRUE
J 0
(-8050 4275);
DISPLAY 0.872340 (-8050 4275);
PAINT GREEN (-8050 4275);
DISPLAY INVISIBLE (-8050 4275);
FORCEPROP 1 LAST COMMENT_BODY TRUE
J 0
(-8250 4300);
DISPLAY 0.872340 (-8250 4300);
PAINT GREEN (-8250 4300);
DISPLAY INVISIBLE (-8250 4300);
FORCEPROP 2 LAST PATH I181
J 0
(-8325 4475);
DISPLAY 0.808511 (-8325 4475);
DISPLAY INVISIBLE (-8325 4475);
FORCEADD OFFPAGE..1
(-8375 4600);
FORCEPROP 2 LAST $XR0 13 
J 0
(-8626 4600);
DISPLAY 0.638298 (-8626 4600);
PAINT MONO (-8626 4600);
FORCEPROP 2 LAST CDS_LIB mstr_standard
J 0
(-8375 4600);
DISPLAY 0.723404 (-8375 4600);
PAINT MONO (-8375 4600);
DISPLAY INVISIBLE (-8375 4600);
FORCEPROP 1 LAST OFFPAGE TRUE
J 0
(-8050 4475);
DISPLAY 0.872340 (-8050 4475);
PAINT GREEN (-8050 4475);
DISPLAY INVISIBLE (-8050 4475);
FORCEPROP 1 LAST COMMENT_BODY TRUE
J 0
(-8250 4500);
DISPLAY 0.872340 (-8250 4500);
PAINT GREEN (-8250 4500);
DISPLAY INVISIBLE (-8250 4500);
FORCEPROP 2 LAST PATH I182
J 0
(-8325 4675);
DISPLAY 0.808511 (-8325 4675);
DISPLAY INVISIBLE (-8325 4675);
FORCEADD OFFPAGE..1
(-8375 4550);
FORCEPROP 2 LAST $XR0 13 
J 0
(-8626 4550);
DISPLAY 0.638298 (-8626 4550);
PAINT MONO (-8626 4550);
FORCEPROP 2 LAST CDS_LIB mstr_standard
J 0
(-8375 4550);
DISPLAY 0.808511 (-8375 4550);
DISPLAY INVISIBLE (-8375 4550);
FORCEPROP 1 LAST OFFPAGE TRUE
J 0
(-8050 4425);
DISPLAY 0.872340 (-8050 4425);
PAINT GREEN (-8050 4425);
DISPLAY INVISIBLE (-8050 4425);
FORCEPROP 1 LAST COMMENT_BODY TRUE
J 0
(-8250 4450);
DISPLAY 0.872340 (-8250 4450);
PAINT GREEN (-8250 4450);
DISPLAY INVISIBLE (-8250 4450);
FORCEPROP 2 LAST PATH I183
J 0
(-8325 4625);
DISPLAY 0.808511 (-8325 4625);
DISPLAY INVISIBLE (-8325 4625);
FORCEADD OFFPAGE..1
(-8375 4450);
FORCEPROP 2 LAST $XR0 13 
J 0
(-8626 4450);
DISPLAY 0.638298 (-8626 4450);
PAINT MONO (-8626 4450);
FORCEPROP 2 LAST CDS_LIB mstr_standard
J 0
(-8375 4450);
DISPLAY 0.723404 (-8375 4450);
PAINT MONO (-8375 4450);
DISPLAY INVISIBLE (-8375 4450);
FORCEPROP 1 LAST OFFPAGE TRUE
J 0
(-8050 4325);
DISPLAY 0.872340 (-8050 4325);
PAINT GREEN (-8050 4325);
DISPLAY INVISIBLE (-8050 4325);
FORCEPROP 1 LAST COMMENT_BODY TRUE
J 0
(-8250 4350);
DISPLAY 0.872340 (-8250 4350);
PAINT GREEN (-8250 4350);
DISPLAY INVISIBLE (-8250 4350);
FORCEPROP 2 LAST PATH I184
J 0
(-8325 4525);
DISPLAY 0.808511 (-8325 4525);
DISPLAY INVISIBLE (-8325 4525);
FORCEADD OFFPAGE..1
(-8375 4700);
FORCEPROP 2 LAST $XR0 13 
J 0
(-8626 4700);
DISPLAY 0.638298 (-8626 4700);
PAINT MONO (-8626 4700);
FORCEPROP 2 LAST CDS_LIB mstr_standard
J 0
(-8375 4700);
DISPLAY 0.808511 (-8375 4700);
DISPLAY INVISIBLE (-8375 4700);
FORCEPROP 1 LAST OFFPAGE TRUE
J 0
(-8050 4575);
DISPLAY 0.872340 (-8050 4575);
PAINT GREEN (-8050 4575);
DISPLAY INVISIBLE (-8050 4575);
FORCEPROP 1 LAST COMMENT_BODY TRUE
J 0
(-8250 4600);
DISPLAY 0.872340 (-8250 4600);
PAINT GREEN (-8250 4600);
DISPLAY INVISIBLE (-8250 4600);
FORCEPROP 2 LAST PATH I185
J 0
(-8325 4775);
DISPLAY 0.808511 (-8325 4775);
DISPLAY INVISIBLE (-8325 4775);
FORCEADD OFFPAGE..1
(-8375 4750);
FORCEPROP 2 LAST $XR0 13 
J 0
(-8626 4750);
DISPLAY 0.638298 (-8626 4750);
PAINT MONO (-8626 4750);
FORCEPROP 2 LAST CDS_LIB mstr_standard
J 0
(-8375 4750);
DISPLAY 0.723404 (-8375 4750);
PAINT MONO (-8375 4750);
DISPLAY INVISIBLE (-8375 4750);
FORCEPROP 1 LAST OFFPAGE TRUE
J 0
(-8050 4625);
DISPLAY 0.872340 (-8050 4625);
PAINT GREEN (-8050 4625);
DISPLAY INVISIBLE (-8050 4625);
FORCEPROP 1 LAST COMMENT_BODY TRUE
J 0
(-8250 4650);
DISPLAY 0.872340 (-8250 4650);
PAINT GREEN (-8250 4650);
DISPLAY INVISIBLE (-8250 4650);
FORCEPROP 2 LAST PATH I186
J 0
(-8325 4825);
DISPLAY 0.808511 (-8325 4825);
DISPLAY INVISIBLE (-8325 4825);
FORCEADD OFFPAGE..1
(-8375 5200);
FORCEPROP 2 LAST $XR0 13 
J 0
(-8626 5200);
DISPLAY 0.638298 (-8626 5200);
PAINT MONO (-8626 5200);
FORCEPROP 2 LAST CDS_LIB mstr_standard
J 0
(-8375 5200);
DISPLAY 0.723404 (-8375 5200);
PAINT MONO (-8375 5200);
DISPLAY INVISIBLE (-8375 5200);
FORCEPROP 1 LAST OFFPAGE TRUE
J 0
(-8050 5075);
DISPLAY 0.872340 (-8050 5075);
PAINT GREEN (-8050 5075);
DISPLAY INVISIBLE (-8050 5075);
FORCEPROP 1 LAST COMMENT_BODY TRUE
J 0
(-8250 5100);
DISPLAY 0.872340 (-8250 5100);
PAINT GREEN (-8250 5100);
DISPLAY INVISIBLE (-8250 5100);
FORCEPROP 2 LAST PATH I187
J 0
(-8325 5275);
DISPLAY 0.808511 (-8325 5275);
DISPLAY INVISIBLE (-8325 5275);
FORCEADD OFFPAGE..1
(-8375 5600);
FORCEPROP 2 LAST $XR0 13 
J 0
(-8626 5600);
DISPLAY 0.638298 (-8626 5600);
PAINT MONO (-8626 5600);
FORCEPROP 2 LAST CDS_LIB mstr_standard
J 0
(-8375 5600);
DISPLAY 0.723404 (-8375 5600);
PAINT MONO (-8375 5600);
DISPLAY INVISIBLE (-8375 5600);
FORCEPROP 1 LAST OFFPAGE TRUE
J 0
(-8050 5475);
DISPLAY 0.872340 (-8050 5475);
PAINT GREEN (-8050 5475);
DISPLAY INVISIBLE (-8050 5475);
FORCEPROP 1 LAST COMMENT_BODY TRUE
J 0
(-8250 5500);
DISPLAY 0.872340 (-8250 5500);
PAINT GREEN (-8250 5500);
DISPLAY INVISIBLE (-8250 5500);
FORCEPROP 2 LAST PATH I188
J 0
(-8325 5675);
DISPLAY 0.808511 (-8325 5675);
DISPLAY INVISIBLE (-8325 5675);
FORCEADD TAP..1
R 2
(-7775 3350);
FORCEPROP 3 LASTPIN (-7725 3350) SIG_NAME M_D_CPU0_SB_CB<0>
J 0
(-7715 3360);
DISPLAY 0.659574 (-7715 3360);
PAINT MONO (-7715 3360);
DISPLAY INVISIBLE (-7715 3360);
FORCEPROP 1 LASTPIN (-7725 3350) BN 0
J 2
(-7713 3358);
DISPLAY 0.489362 (-7713 3358);
PAINT GREEN (-7713 3358);
FORCEPROP 2 LAST CDS_LIB mstr_standard
J 0
(-7775 3350);
DISPLAY 0.723404 (-7775 3350);
PAINT MONO (-7775 3350);
DISPLAY INVISIBLE (-7775 3350);
FORCEPROP 1 LAST BODY_TYPE PLUMBING
J 2
(-7775 3400);
DISPLAY 0.872340 (-7775 3400);
PAINT GREEN (-7775 3400);
DISPLAY INVISIBLE (-7775 3400);
FORCEPROP 1 LAST HDL_TAP TRUE
J 2
(-8100 3225);
DISPLAY 0.872340 (-8100 3225);
DISPLAY INVISIBLE (-8100 3225);
FORCEPROP 1 LAST PATH I189
J 2
(-7773 3350);
DISPLAY 0.872340 (-7773 3350);
PAINT GREEN (-7773 3350);
DISPLAY INVISIBLE (-7773 3350);
FORCEADD TAP..1
R 2
(-7775 3400);
FORCEPROP 3 LASTPIN (-7725 3400) SIG_NAME M_D_CPU0_SB_CB<1>
J 0
(-7715 3410);
DISPLAY 0.659574 (-7715 3410);
PAINT MONO (-7715 3410);
DISPLAY INVISIBLE (-7715 3410);
FORCEPROP 1 LASTPIN (-7725 3400) BN 1
J 2
(-7713 3408);
DISPLAY 0.489362 (-7713 3408);
PAINT GREEN (-7713 3408);
FORCEPROP 2 LAST CDS_LIB mstr_standard
J 0
(-7775 3400);
DISPLAY 0.723404 (-7775 3400);
PAINT MONO (-7775 3400);
DISPLAY INVISIBLE (-7775 3400);
FORCEPROP 1 LAST BODY_TYPE PLUMBING
J 2
(-7775 3450);
DISPLAY 0.872340 (-7775 3450);
PAINT GREEN (-7775 3450);
DISPLAY INVISIBLE (-7775 3450);
FORCEPROP 1 LAST HDL_TAP TRUE
J 2
(-8100 3275);
DISPLAY 0.872340 (-8100 3275);
DISPLAY INVISIBLE (-8100 3275);
FORCEPROP 1 LAST PATH I190
J 2
(-7773 3400);
DISPLAY 0.872340 (-7773 3400);
PAINT GREEN (-7773 3400);
DISPLAY INVISIBLE (-7773 3400);
FORCEADD TAP..1
R 2
(-7775 3500);
FORCEPROP 3 LASTPIN (-7725 3500) SIG_NAME M_D_CPU0_SB_CB<3>
J 0
(-7715 3510);
DISPLAY 0.659574 (-7715 3510);
PAINT MONO (-7715 3510);
DISPLAY INVISIBLE (-7715 3510);
FORCEPROP 1 LASTPIN (-7725 3500) BN 3
J 2
(-7713 3508);
DISPLAY 0.489362 (-7713 3508);
PAINT GREEN (-7713 3508);
FORCEPROP 2 LAST CDS_LIB mstr_standard
J 0
(-7775 3500);
DISPLAY 0.723404 (-7775 3500);
PAINT MONO (-7775 3500);
DISPLAY INVISIBLE (-7775 3500);
FORCEPROP 1 LAST BODY_TYPE PLUMBING
J 2
(-7775 3550);
DISPLAY 0.872340 (-7775 3550);
PAINT GREEN (-7775 3550);
DISPLAY INVISIBLE (-7775 3550);
FORCEPROP 1 LAST HDL_TAP TRUE
J 2
(-8100 3375);
DISPLAY 0.872340 (-8100 3375);
DISPLAY INVISIBLE (-8100 3375);
FORCEPROP 1 LAST PATH I191
J 2
(-7773 3500);
DISPLAY 0.872340 (-7773 3500);
PAINT GREEN (-7773 3500);
DISPLAY INVISIBLE (-7773 3500);
FORCEADD TAP..1
R 2
(-7775 3450);
FORCEPROP 3 LASTPIN (-7725 3450) SIG_NAME M_D_CPU0_SB_CB<2>
J 0
(-7715 3460);
DISPLAY 0.659574 (-7715 3460);
PAINT MONO (-7715 3460);
DISPLAY INVISIBLE (-7715 3460);
FORCEPROP 1 LASTPIN (-7725 3450) BN 2
J 2
(-7713 3458);
DISPLAY 0.489362 (-7713 3458);
PAINT GREEN (-7713 3458);
FORCEPROP 2 LAST CDS_LIB mstr_standard
J 0
(-7775 3450);
DISPLAY 0.723404 (-7775 3450);
PAINT MONO (-7775 3450);
DISPLAY INVISIBLE (-7775 3450);
FORCEPROP 1 LAST BODY_TYPE PLUMBING
J 2
(-7775 3500);
DISPLAY 0.872340 (-7775 3500);
PAINT GREEN (-7775 3500);
DISPLAY INVISIBLE (-7775 3500);
FORCEPROP 1 LAST HDL_TAP TRUE
J 2
(-8100 3325);
DISPLAY 0.872340 (-8100 3325);
DISPLAY INVISIBLE (-8100 3325);
FORCEPROP 1 LAST PATH I192
J 2
(-7773 3450);
DISPLAY 0.872340 (-7773 3450);
PAINT GREEN (-7773 3450);
DISPLAY INVISIBLE (-7773 3450);
FORCEADD TAP..1
R 2
(-7775 3550);
FORCEPROP 3 LASTPIN (-7725 3550) SIG_NAME M_D_CPU0_SB_CB<4>
J 0
(-7715 3560);
DISPLAY 0.659574 (-7715 3560);
PAINT MONO (-7715 3560);
DISPLAY INVISIBLE (-7715 3560);
FORCEPROP 1 LASTPIN (-7725 3550) BN 4
J 2
(-7713 3558);
DISPLAY 0.489362 (-7713 3558);
PAINT GREEN (-7713 3558);
FORCEPROP 2 LAST CDS_LIB mstr_standard
J 0
(-7775 3550);
DISPLAY 0.723404 (-7775 3550);
PAINT MONO (-7775 3550);
DISPLAY INVISIBLE (-7775 3550);
FORCEPROP 1 LAST BODY_TYPE PLUMBING
J 2
(-7775 3600);
DISPLAY 0.872340 (-7775 3600);
PAINT GREEN (-7775 3600);
DISPLAY INVISIBLE (-7775 3600);
FORCEPROP 1 LAST HDL_TAP TRUE
J 2
(-8100 3425);
DISPLAY 0.872340 (-8100 3425);
DISPLAY INVISIBLE (-8100 3425);
FORCEPROP 1 LAST PATH I193
J 2
(-7773 3550);
DISPLAY 0.872340 (-7773 3550);
PAINT GREEN (-7773 3550);
DISPLAY INVISIBLE (-7773 3550);
FORCEADD TAP..1
R 2
(-7775 3600);
FORCEPROP 3 LASTPIN (-7725 3600) SIG_NAME M_D_CPU0_SB_CB<5>
J 0
(-7715 3610);
DISPLAY 0.659574 (-7715 3610);
PAINT MONO (-7715 3610);
DISPLAY INVISIBLE (-7715 3610);
FORCEPROP 1 LASTPIN (-7725 3600) BN 5
J 2
(-7713 3608);
DISPLAY 0.489362 (-7713 3608);
PAINT GREEN (-7713 3608);
FORCEPROP 2 LAST CDS_LIB mstr_standard
J 0
(-7775 3600);
DISPLAY 0.723404 (-7775 3600);
PAINT MONO (-7775 3600);
DISPLAY INVISIBLE (-7775 3600);
FORCEPROP 1 LAST BODY_TYPE PLUMBING
J 2
(-7775 3650);
DISPLAY 0.872340 (-7775 3650);
PAINT GREEN (-7775 3650);
DISPLAY INVISIBLE (-7775 3650);
FORCEPROP 1 LAST HDL_TAP TRUE
J 2
(-8100 3475);
DISPLAY 0.872340 (-8100 3475);
DISPLAY INVISIBLE (-8100 3475);
FORCEPROP 1 LAST PATH I194
J 2
(-7773 3600);
DISPLAY 0.872340 (-7773 3600);
PAINT GREEN (-7773 3600);
DISPLAY INVISIBLE (-7773 3600);
FORCEADD TAP..1
R 2
(-7775 3650);
FORCEPROP 3 LASTPIN (-7725 3650) SIG_NAME M_D_CPU0_SB_CB<6>
J 0
(-7715 3660);
DISPLAY 0.659574 (-7715 3660);
PAINT MONO (-7715 3660);
DISPLAY INVISIBLE (-7715 3660);
FORCEPROP 1 LASTPIN (-7725 3650) BN 6
J 2
(-7713 3658);
DISPLAY 0.489362 (-7713 3658);
PAINT GREEN (-7713 3658);
FORCEPROP 2 LAST CDS_LIB mstr_standard
J 0
(-7775 3650);
DISPLAY 0.723404 (-7775 3650);
PAINT MONO (-7775 3650);
DISPLAY INVISIBLE (-7775 3650);
FORCEPROP 1 LAST BODY_TYPE PLUMBING
J 2
(-7775 3700);
DISPLAY 0.872340 (-7775 3700);
PAINT GREEN (-7775 3700);
DISPLAY INVISIBLE (-7775 3700);
FORCEPROP 1 LAST HDL_TAP TRUE
J 2
(-8100 3525);
DISPLAY 0.872340 (-8100 3525);
DISPLAY INVISIBLE (-8100 3525);
FORCEPROP 1 LAST PATH I195
J 2
(-7773 3650);
DISPLAY 0.872340 (-7773 3650);
PAINT GREEN (-7773 3650);
DISPLAY INVISIBLE (-7773 3650);
FORCEADD TAP..1
R 2
(-7775 3700);
FORCEPROP 3 LASTPIN (-7725 3700) SIG_NAME M_D_CPU0_SB_CB<7>
J 0
(-7715 3710);
DISPLAY 0.659574 (-7715 3710);
PAINT MONO (-7715 3710);
DISPLAY INVISIBLE (-7715 3710);
FORCEPROP 1 LASTPIN (-7725 3700) BN 7
J 2
(-7713 3708);
DISPLAY 0.489362 (-7713 3708);
PAINT GREEN (-7713 3708);
FORCEPROP 2 LAST CDS_LIB mstr_standard
J 0
(-7775 3700);
DISPLAY 0.723404 (-7775 3700);
PAINT MONO (-7775 3700);
DISPLAY INVISIBLE (-7775 3700);
FORCEPROP 1 LAST BODY_TYPE PLUMBING
J 2
(-7775 3750);
DISPLAY 0.872340 (-7775 3750);
PAINT GREEN (-7775 3750);
DISPLAY INVISIBLE (-7775 3750);
FORCEPROP 1 LAST HDL_TAP TRUE
J 2
(-8100 3575);
DISPLAY 0.872340 (-8100 3575);
DISPLAY INVISIBLE (-8100 3575);
FORCEPROP 1 LAST PATH I196
J 2
(-7773 3700);
DISPLAY 0.872340 (-7773 3700);
PAINT GREEN (-7773 3700);
DISPLAY INVISIBLE (-7773 3700);
FORCEADD TAP..1
R 2
(-7775 3800);
FORCEPROP 3 LASTPIN (-7725 3800) SIG_NAME M_D_CPU0_SA_CB<0>
J 0
(-7715 3810);
DISPLAY 0.659574 (-7715 3810);
PAINT MONO (-7715 3810);
DISPLAY INVISIBLE (-7715 3810);
FORCEPROP 1 LASTPIN (-7725 3800) BN 0
J 2
(-7713 3808);
DISPLAY 0.489362 (-7713 3808);
PAINT GREEN (-7713 3808);
FORCEPROP 2 LAST CDS_LIB mstr_standard
J 0
(-7775 3800);
DISPLAY 0.723404 (-7775 3800);
PAINT MONO (-7775 3800);
DISPLAY INVISIBLE (-7775 3800);
FORCEPROP 1 LAST BODY_TYPE PLUMBING
J 2
(-7775 3850);
DISPLAY 0.872340 (-7775 3850);
PAINT GREEN (-7775 3850);
DISPLAY INVISIBLE (-7775 3850);
FORCEPROP 1 LAST HDL_TAP TRUE
J 2
(-8100 3675);
DISPLAY 0.872340 (-8100 3675);
DISPLAY INVISIBLE (-8100 3675);
FORCEPROP 1 LAST PATH I197
J 2
(-7773 3800);
DISPLAY 0.872340 (-7773 3800);
PAINT GREEN (-7773 3800);
DISPLAY INVISIBLE (-7773 3800);
FORCEADD TAP..1
R 2
(-7775 3850);
FORCEPROP 3 LASTPIN (-7725 3850) SIG_NAME M_D_CPU0_SA_CB<1>
J 0
(-7715 3860);
DISPLAY 0.659574 (-7715 3860);
PAINT MONO (-7715 3860);
DISPLAY INVISIBLE (-7715 3860);
FORCEPROP 1 LASTPIN (-7725 3850) BN 1
J 2
(-7713 3858);
DISPLAY 0.489362 (-7713 3858);
PAINT GREEN (-7713 3858);
FORCEPROP 2 LAST CDS_LIB mstr_standard
J 0
(-7775 3850);
DISPLAY 0.723404 (-7775 3850);
PAINT MONO (-7775 3850);
DISPLAY INVISIBLE (-7775 3850);
FORCEPROP 1 LAST BODY_TYPE PLUMBING
J 2
(-7775 3900);
DISPLAY 0.872340 (-7775 3900);
PAINT GREEN (-7775 3900);
DISPLAY INVISIBLE (-7775 3900);
FORCEPROP 1 LAST HDL_TAP TRUE
J 2
(-8100 3725);
DISPLAY 0.872340 (-8100 3725);
DISPLAY INVISIBLE (-8100 3725);
FORCEPROP 1 LAST PATH I198
J 2
(-7773 3850);
DISPLAY 0.872340 (-7773 3850);
PAINT GREEN (-7773 3850);
DISPLAY INVISIBLE (-7773 3850);
FORCEADD TAP..1
R 2
(-7775 3950);
FORCEPROP 3 LASTPIN (-7725 3950) SIG_NAME M_D_CPU0_SA_CB<3>
J 0
(-7715 3960);
DISPLAY 0.659574 (-7715 3960);
PAINT MONO (-7715 3960);
DISPLAY INVISIBLE (-7715 3960);
FORCEPROP 1 LASTPIN (-7725 3950) BN 3
J 2
(-7713 3958);
DISPLAY 0.489362 (-7713 3958);
PAINT GREEN (-7713 3958);
FORCEPROP 2 LAST CDS_LIB mstr_standard
J 0
(-7775 3950);
DISPLAY 0.723404 (-7775 3950);
PAINT MONO (-7775 3950);
DISPLAY INVISIBLE (-7775 3950);
FORCEPROP 1 LAST BODY_TYPE PLUMBING
J 2
(-7775 4000);
DISPLAY 0.872340 (-7775 4000);
PAINT GREEN (-7775 4000);
DISPLAY INVISIBLE (-7775 4000);
FORCEPROP 1 LAST HDL_TAP TRUE
J 2
(-8100 3825);
DISPLAY 0.872340 (-8100 3825);
DISPLAY INVISIBLE (-8100 3825);
FORCEPROP 1 LAST PATH I199
J 2
(-7773 3950);
DISPLAY 0.872340 (-7773 3950);
PAINT GREEN (-7773 3950);
DISPLAY INVISIBLE (-7773 3950);
FORCEADD TAP..1
R 2
(-7775 3900);
FORCEPROP 3 LASTPIN (-7725 3900) SIG_NAME M_D_CPU0_SA_CB<2>
J 0
(-7715 3910);
DISPLAY 0.659574 (-7715 3910);
PAINT MONO (-7715 3910);
DISPLAY INVISIBLE (-7715 3910);
FORCEPROP 1 LASTPIN (-7725 3900) BN 2
J 2
(-7713 3908);
DISPLAY 0.489362 (-7713 3908);
PAINT GREEN (-7713 3908);
FORCEPROP 2 LAST CDS_LIB mstr_standard
J 0
(-7775 3900);
DISPLAY 0.723404 (-7775 3900);
PAINT MONO (-7775 3900);
DISPLAY INVISIBLE (-7775 3900);
FORCEPROP 1 LAST BODY_TYPE PLUMBING
J 2
(-7775 3950);
DISPLAY 0.872340 (-7775 3950);
PAINT GREEN (-7775 3950);
DISPLAY INVISIBLE (-7775 3950);
FORCEPROP 1 LAST HDL_TAP TRUE
J 2
(-8100 3775);
DISPLAY 0.872340 (-8100 3775);
DISPLAY INVISIBLE (-8100 3775);
FORCEPROP 1 LAST PATH I200
J 2
(-7773 3900);
DISPLAY 0.872340 (-7773 3900);
PAINT GREEN (-7773 3900);
DISPLAY INVISIBLE (-7773 3900);
FORCEADD TAP..1
R 2
(-7775 4000);
FORCEPROP 3 LASTPIN (-7725 4000) SIG_NAME M_D_CPU0_SA_CB<4>
J 0
(-7715 4010);
DISPLAY 0.659574 (-7715 4010);
PAINT MONO (-7715 4010);
DISPLAY INVISIBLE (-7715 4010);
FORCEPROP 1 LASTPIN (-7725 4000) BN 4
J 2
(-7713 4008);
DISPLAY 0.489362 (-7713 4008);
PAINT GREEN (-7713 4008);
FORCEPROP 2 LAST CDS_LIB mstr_standard
J 0
(-7775 4000);
DISPLAY 0.723404 (-7775 4000);
PAINT MONO (-7775 4000);
DISPLAY INVISIBLE (-7775 4000);
FORCEPROP 1 LAST BODY_TYPE PLUMBING
J 2
(-7775 4050);
DISPLAY 0.872340 (-7775 4050);
PAINT GREEN (-7775 4050);
DISPLAY INVISIBLE (-7775 4050);
FORCEPROP 1 LAST HDL_TAP TRUE
J 2
(-8100 3875);
DISPLAY 0.872340 (-8100 3875);
DISPLAY INVISIBLE (-8100 3875);
FORCEPROP 1 LAST PATH I201
J 2
(-7773 4000);
DISPLAY 0.872340 (-7773 4000);
PAINT GREEN (-7773 4000);
DISPLAY INVISIBLE (-7773 4000);
FORCEADD TAP..1
R 2
(-7775 4050);
FORCEPROP 3 LASTPIN (-7725 4050) SIG_NAME M_D_CPU0_SA_CB<5>
J 0
(-7715 4060);
DISPLAY 0.659574 (-7715 4060);
PAINT MONO (-7715 4060);
DISPLAY INVISIBLE (-7715 4060);
FORCEPROP 1 LASTPIN (-7725 4050) BN 5
J 2
(-7713 4058);
DISPLAY 0.489362 (-7713 4058);
PAINT GREEN (-7713 4058);
FORCEPROP 2 LAST CDS_LIB mstr_standard
J 0
(-7775 4050);
DISPLAY 0.723404 (-7775 4050);
PAINT MONO (-7775 4050);
DISPLAY INVISIBLE (-7775 4050);
FORCEPROP 1 LAST BODY_TYPE PLUMBING
J 2
(-7775 4100);
DISPLAY 0.872340 (-7775 4100);
PAINT GREEN (-7775 4100);
DISPLAY INVISIBLE (-7775 4100);
FORCEPROP 1 LAST HDL_TAP TRUE
J 2
(-8100 3925);
DISPLAY 0.872340 (-8100 3925);
DISPLAY INVISIBLE (-8100 3925);
FORCEPROP 1 LAST PATH I202
J 2
(-7773 4050);
DISPLAY 0.872340 (-7773 4050);
PAINT GREEN (-7773 4050);
DISPLAY INVISIBLE (-7773 4050);
FORCEADD TAP..1
R 2
(-7775 4100);
FORCEPROP 3 LASTPIN (-7725 4100) SIG_NAME M_D_CPU0_SA_CB<6>
J 0
(-7715 4110);
DISPLAY 0.659574 (-7715 4110);
PAINT MONO (-7715 4110);
DISPLAY INVISIBLE (-7715 4110);
FORCEPROP 1 LASTPIN (-7725 4100) BN 6
J 2
(-7713 4108);
DISPLAY 0.489362 (-7713 4108);
PAINT GREEN (-7713 4108);
FORCEPROP 2 LAST CDS_LIB mstr_standard
J 0
(-7775 4100);
DISPLAY 0.723404 (-7775 4100);
PAINT MONO (-7775 4100);
DISPLAY INVISIBLE (-7775 4100);
FORCEPROP 1 LAST BODY_TYPE PLUMBING
J 2
(-7775 4150);
DISPLAY 0.872340 (-7775 4150);
PAINT GREEN (-7775 4150);
DISPLAY INVISIBLE (-7775 4150);
FORCEPROP 1 LAST HDL_TAP TRUE
J 2
(-8100 3975);
DISPLAY 0.872340 (-8100 3975);
DISPLAY INVISIBLE (-8100 3975);
FORCEPROP 1 LAST PATH I203
J 2
(-7773 4100);
DISPLAY 0.872340 (-7773 4100);
PAINT GREEN (-7773 4100);
DISPLAY INVISIBLE (-7773 4100);
FORCEADD TAP..1
(-6075 2350);
FORCEPROP 3 LASTPIN (-6125 2350) SIG_NAME M_D_CPU0_SB_DQ<0>
J 0
(-6115 2360);
DISPLAY 0.659574 (-6115 2360);
PAINT MONO (-6115 2360);
DISPLAY INVISIBLE (-6115 2360);
FORCEPROP 1 LASTPIN (-6125 2350) BN 0
J 0
(-6137 2358);
DISPLAY 0.489362 (-6137 2358);
PAINT GREEN (-6137 2358);
FORCEPROP 2 LAST CDS_LIB mstr_standard
J 0
(-6075 2350);
DISPLAY 0.723404 (-6075 2350);
PAINT MONO (-6075 2350);
DISPLAY INVISIBLE (-6075 2350);
FORCEPROP 1 LAST BODY_TYPE PLUMBING
J 0
(-6075 2400);
DISPLAY 0.872340 (-6075 2400);
PAINT GREEN (-6075 2400);
DISPLAY INVISIBLE (-6075 2400);
FORCEPROP 1 LAST HDL_TAP TRUE
J 0
(-5750 2225);
DISPLAY 0.872340 (-5750 2225);
DISPLAY INVISIBLE (-5750 2225);
FORCEPROP 1 LAST PATH I204
J 0
(-6077 2350);
DISPLAY 0.872340 (-6077 2350);
PAINT GREEN (-6077 2350);
DISPLAY INVISIBLE (-6077 2350);
FORCEADD TAP..1
(-6075 2400);
FORCEPROP 3 LASTPIN (-6125 2400) SIG_NAME M_D_CPU0_SB_DQ<1>
J 0
(-6115 2410);
DISPLAY 0.659574 (-6115 2410);
PAINT MONO (-6115 2410);
DISPLAY INVISIBLE (-6115 2410);
FORCEPROP 1 LASTPIN (-6125 2400) BN 1
J 0
(-6137 2408);
DISPLAY 0.489362 (-6137 2408);
PAINT GREEN (-6137 2408);
FORCEPROP 2 LAST CDS_LIB mstr_standard
J 0
(-6075 2400);
DISPLAY 0.723404 (-6075 2400);
PAINT MONO (-6075 2400);
DISPLAY INVISIBLE (-6075 2400);
FORCEPROP 1 LAST BODY_TYPE PLUMBING
J 0
(-6075 2450);
DISPLAY 0.872340 (-6075 2450);
PAINT GREEN (-6075 2450);
DISPLAY INVISIBLE (-6075 2450);
FORCEPROP 1 LAST HDL_TAP TRUE
J 0
(-5750 2275);
DISPLAY 0.872340 (-5750 2275);
DISPLAY INVISIBLE (-5750 2275);
FORCEPROP 1 LAST PATH I205
J 0
(-6077 2400);
DISPLAY 0.872340 (-6077 2400);
PAINT GREEN (-6077 2400);
DISPLAY INVISIBLE (-6077 2400);
FORCEADD TAP..1
(-6075 2450);
FORCEPROP 3 LASTPIN (-6125 2450) SIG_NAME M_D_CPU0_SB_DQ<2>
J 0
(-6115 2460);
DISPLAY 0.659574 (-6115 2460);
PAINT MONO (-6115 2460);
DISPLAY INVISIBLE (-6115 2460);
FORCEPROP 1 LASTPIN (-6125 2450) BN 2
J 0
(-6137 2458);
DISPLAY 0.489362 (-6137 2458);
PAINT GREEN (-6137 2458);
FORCEPROP 2 LAST CDS_LIB mstr_standard
J 0
(-6075 2450);
DISPLAY 0.723404 (-6075 2450);
PAINT MONO (-6075 2450);
DISPLAY INVISIBLE (-6075 2450);
FORCEPROP 1 LAST BODY_TYPE PLUMBING
J 0
(-6075 2500);
DISPLAY 0.872340 (-6075 2500);
PAINT GREEN (-6075 2500);
DISPLAY INVISIBLE (-6075 2500);
FORCEPROP 1 LAST HDL_TAP TRUE
J 0
(-5750 2325);
DISPLAY 0.872340 (-5750 2325);
DISPLAY INVISIBLE (-5750 2325);
FORCEPROP 1 LAST PATH I206
J 0
(-6077 2450);
DISPLAY 0.872340 (-6077 2450);
PAINT GREEN (-6077 2450);
DISPLAY INVISIBLE (-6077 2450);
FORCEADD TAP..1
(-6075 2500);
FORCEPROP 3 LASTPIN (-6125 2500) SIG_NAME M_D_CPU0_SB_DQ<3>
J 0
(-6115 2510);
DISPLAY 0.659574 (-6115 2510);
PAINT MONO (-6115 2510);
DISPLAY INVISIBLE (-6115 2510);
FORCEPROP 1 LASTPIN (-6125 2500) BN 3
J 0
(-6137 2508);
DISPLAY 0.489362 (-6137 2508);
PAINT GREEN (-6137 2508);
FORCEPROP 2 LAST CDS_LIB mstr_standard
J 0
(-6075 2500);
DISPLAY 0.723404 (-6075 2500);
PAINT MONO (-6075 2500);
DISPLAY INVISIBLE (-6075 2500);
FORCEPROP 1 LAST BODY_TYPE PLUMBING
J 0
(-6075 2550);
DISPLAY 0.872340 (-6075 2550);
PAINT GREEN (-6075 2550);
DISPLAY INVISIBLE (-6075 2550);
FORCEPROP 1 LAST HDL_TAP TRUE
J 0
(-5750 2375);
DISPLAY 0.872340 (-5750 2375);
DISPLAY INVISIBLE (-5750 2375);
FORCEPROP 1 LAST PATH I207
J 0
(-6077 2500);
DISPLAY 0.872340 (-6077 2500);
PAINT GREEN (-6077 2500);
DISPLAY INVISIBLE (-6077 2500);
FORCEADD TAP..1
(-6075 2550);
FORCEPROP 3 LASTPIN (-6125 2550) SIG_NAME M_D_CPU0_SB_DQ<4>
J 0
(-6115 2560);
DISPLAY 0.659574 (-6115 2560);
PAINT MONO (-6115 2560);
DISPLAY INVISIBLE (-6115 2560);
FORCEPROP 1 LASTPIN (-6125 2550) BN 4
J 0
(-6137 2558);
DISPLAY 0.489362 (-6137 2558);
PAINT GREEN (-6137 2558);
FORCEPROP 2 LAST CDS_LIB mstr_standard
J 0
(-6075 2550);
DISPLAY 0.723404 (-6075 2550);
PAINT MONO (-6075 2550);
DISPLAY INVISIBLE (-6075 2550);
FORCEPROP 1 LAST BODY_TYPE PLUMBING
J 0
(-6075 2600);
DISPLAY 0.872340 (-6075 2600);
PAINT GREEN (-6075 2600);
DISPLAY INVISIBLE (-6075 2600);
FORCEPROP 1 LAST HDL_TAP TRUE
J 0
(-5750 2425);
DISPLAY 0.872340 (-5750 2425);
DISPLAY INVISIBLE (-5750 2425);
FORCEPROP 1 LAST PATH I208
J 0
(-6077 2550);
DISPLAY 0.872340 (-6077 2550);
PAINT GREEN (-6077 2550);
DISPLAY INVISIBLE (-6077 2550);
FORCEADD TAP..1
(-6075 2600);
FORCEPROP 3 LASTPIN (-6125 2600) SIG_NAME M_D_CPU0_SB_DQ<5>
J 0
(-6115 2610);
DISPLAY 0.659574 (-6115 2610);
PAINT MONO (-6115 2610);
DISPLAY INVISIBLE (-6115 2610);
FORCEPROP 1 LASTPIN (-6125 2600) BN 5
J 0
(-6137 2608);
DISPLAY 0.489362 (-6137 2608);
PAINT GREEN (-6137 2608);
FORCEPROP 2 LAST CDS_LIB mstr_standard
J 0
(-6075 2600);
DISPLAY 0.723404 (-6075 2600);
PAINT MONO (-6075 2600);
DISPLAY INVISIBLE (-6075 2600);
FORCEPROP 1 LAST BODY_TYPE PLUMBING
J 0
(-6075 2650);
DISPLAY 0.872340 (-6075 2650);
PAINT GREEN (-6075 2650);
DISPLAY INVISIBLE (-6075 2650);
FORCEPROP 1 LAST HDL_TAP TRUE
J 0
(-5750 2475);
DISPLAY 0.872340 (-5750 2475);
DISPLAY INVISIBLE (-5750 2475);
FORCEPROP 1 LAST PATH I209
J 0
(-6077 2600);
DISPLAY 0.872340 (-6077 2600);
PAINT GREEN (-6077 2600);
DISPLAY INVISIBLE (-6077 2600);
FORCEADD TAP..1
(-6075 2700);
FORCEPROP 3 LASTPIN (-6125 2700) SIG_NAME M_D_CPU0_SB_DQ<7>
J 0
(-6115 2710);
DISPLAY 0.659574 (-6115 2710);
PAINT MONO (-6115 2710);
DISPLAY INVISIBLE (-6115 2710);
FORCEPROP 1 LASTPIN (-6125 2700) BN 7
J 0
(-6137 2708);
DISPLAY 0.489362 (-6137 2708);
PAINT GREEN (-6137 2708);
FORCEPROP 2 LAST CDS_LIB mstr_standard
J 0
(-6075 2700);
DISPLAY 0.723404 (-6075 2700);
PAINT MONO (-6075 2700);
DISPLAY INVISIBLE (-6075 2700);
FORCEPROP 1 LAST BODY_TYPE PLUMBING
J 0
(-6075 2750);
DISPLAY 0.872340 (-6075 2750);
PAINT GREEN (-6075 2750);
DISPLAY INVISIBLE (-6075 2750);
FORCEPROP 1 LAST HDL_TAP TRUE
J 0
(-5750 2575);
DISPLAY 0.872340 (-5750 2575);
DISPLAY INVISIBLE (-5750 2575);
FORCEPROP 1 LAST PATH I210
J 0
(-6077 2700);
DISPLAY 0.872340 (-6077 2700);
PAINT GREEN (-6077 2700);
DISPLAY INVISIBLE (-6077 2700);
FORCEADD TAP..1
(-6075 2650);
FORCEPROP 3 LASTPIN (-6125 2650) SIG_NAME M_D_CPU0_SB_DQ<6>
J 0
(-6115 2660);
DISPLAY 0.659574 (-6115 2660);
PAINT MONO (-6115 2660);
DISPLAY INVISIBLE (-6115 2660);
FORCEPROP 1 LASTPIN (-6125 2650) BN 6
J 0
(-6137 2658);
DISPLAY 0.489362 (-6137 2658);
PAINT GREEN (-6137 2658);
FORCEPROP 2 LAST CDS_LIB mstr_standard
J 0
(-6075 2650);
DISPLAY 0.723404 (-6075 2650);
PAINT MONO (-6075 2650);
DISPLAY INVISIBLE (-6075 2650);
FORCEPROP 1 LAST BODY_TYPE PLUMBING
J 0
(-6075 2700);
DISPLAY 0.872340 (-6075 2700);
PAINT GREEN (-6075 2700);
DISPLAY INVISIBLE (-6075 2700);
FORCEPROP 1 LAST HDL_TAP TRUE
J 0
(-5750 2525);
DISPLAY 0.872340 (-5750 2525);
DISPLAY INVISIBLE (-5750 2525);
FORCEPROP 1 LAST PATH I211
J 0
(-6077 2650);
DISPLAY 0.872340 (-6077 2650);
PAINT GREEN (-6077 2650);
DISPLAY INVISIBLE (-6077 2650);
FORCEADD TAP..1
(-6075 2750);
FORCEPROP 3 LASTPIN (-6125 2750) SIG_NAME M_D_CPU0_SB_DQ<8>
J 0
(-6115 2760);
DISPLAY 0.659574 (-6115 2760);
PAINT MONO (-6115 2760);
DISPLAY INVISIBLE (-6115 2760);
FORCEPROP 1 LASTPIN (-6125 2750) BN 8
J 0
(-6137 2758);
DISPLAY 0.489362 (-6137 2758);
PAINT GREEN (-6137 2758);
FORCEPROP 2 LAST CDS_LIB mstr_standard
J 0
(-6075 2750);
DISPLAY 0.723404 (-6075 2750);
PAINT MONO (-6075 2750);
DISPLAY INVISIBLE (-6075 2750);
FORCEPROP 1 LAST BODY_TYPE PLUMBING
J 0
(-6075 2800);
DISPLAY 0.872340 (-6075 2800);
PAINT GREEN (-6075 2800);
DISPLAY INVISIBLE (-6075 2800);
FORCEPROP 1 LAST HDL_TAP TRUE
J 0
(-5750 2625);
DISPLAY 0.872340 (-5750 2625);
DISPLAY INVISIBLE (-5750 2625);
FORCEPROP 1 LAST PATH I212
J 0
(-6077 2750);
DISPLAY 0.872340 (-6077 2750);
PAINT GREEN (-6077 2750);
DISPLAY INVISIBLE (-6077 2750);
FORCEADD TAP..1
(-6075 2800);
FORCEPROP 3 LASTPIN (-6125 2800) SIG_NAME M_D_CPU0_SB_DQ<9>
J 0
(-6115 2810);
DISPLAY 0.659574 (-6115 2810);
PAINT MONO (-6115 2810);
DISPLAY INVISIBLE (-6115 2810);
FORCEPROP 1 LASTPIN (-6125 2800) BN 9
J 0
(-6137 2808);
DISPLAY 0.489362 (-6137 2808);
PAINT GREEN (-6137 2808);
FORCEPROP 2 LAST CDS_LIB mstr_standard
J 0
(-6075 2800);
DISPLAY 0.723404 (-6075 2800);
PAINT MONO (-6075 2800);
DISPLAY INVISIBLE (-6075 2800);
FORCEPROP 1 LAST BODY_TYPE PLUMBING
J 0
(-6075 2850);
DISPLAY 0.872340 (-6075 2850);
PAINT GREEN (-6075 2850);
DISPLAY INVISIBLE (-6075 2850);
FORCEPROP 1 LAST HDL_TAP TRUE
J 0
(-5750 2675);
DISPLAY 0.872340 (-5750 2675);
DISPLAY INVISIBLE (-5750 2675);
FORCEPROP 1 LAST PATH I213
J 0
(-6077 2800);
DISPLAY 0.872340 (-6077 2800);
PAINT GREEN (-6077 2800);
DISPLAY INVISIBLE (-6077 2800);
FORCEADD TAP..1
(-6075 2850);
FORCEPROP 3 LASTPIN (-6125 2850) SIG_NAME M_D_CPU0_SB_DQ<10>
J 0
(-6115 2860);
DISPLAY 0.659574 (-6115 2860);
PAINT MONO (-6115 2860);
DISPLAY INVISIBLE (-6115 2860);
FORCEPROP 1 LASTPIN (-6125 2850) BN 10
J 0
(-6137 2858);
DISPLAY 0.489362 (-6137 2858);
PAINT GREEN (-6137 2858);
FORCEPROP 2 LAST CDS_LIB mstr_standard
J 0
(-6075 2850);
DISPLAY 0.723404 (-6075 2850);
PAINT MONO (-6075 2850);
DISPLAY INVISIBLE (-6075 2850);
FORCEPROP 1 LAST BODY_TYPE PLUMBING
J 0
(-6075 2900);
DISPLAY 0.872340 (-6075 2900);
PAINT GREEN (-6075 2900);
DISPLAY INVISIBLE (-6075 2900);
FORCEPROP 1 LAST HDL_TAP TRUE
J 0
(-5750 2725);
DISPLAY 0.872340 (-5750 2725);
DISPLAY INVISIBLE (-5750 2725);
FORCEPROP 1 LAST PATH I214
J 0
(-6077 2850);
DISPLAY 0.872340 (-6077 2850);
PAINT GREEN (-6077 2850);
DISPLAY INVISIBLE (-6077 2850);
FORCEADD TAP..1
(-6075 2950);
FORCEPROP 3 LASTPIN (-6125 2950) SIG_NAME M_D_CPU0_SB_DQ<12>
J 0
(-6115 2960);
DISPLAY 0.659574 (-6115 2960);
PAINT MONO (-6115 2960);
DISPLAY INVISIBLE (-6115 2960);
FORCEPROP 1 LASTPIN (-6125 2950) BN 12
J 0
(-6137 2958);
DISPLAY 0.489362 (-6137 2958);
PAINT GREEN (-6137 2958);
FORCEPROP 2 LAST CDS_LIB mstr_standard
J 0
(-6075 2950);
DISPLAY 0.723404 (-6075 2950);
PAINT MONO (-6075 2950);
DISPLAY INVISIBLE (-6075 2950);
FORCEPROP 1 LAST BODY_TYPE PLUMBING
J 0
(-6075 3000);
DISPLAY 0.872340 (-6075 3000);
PAINT GREEN (-6075 3000);
DISPLAY INVISIBLE (-6075 3000);
FORCEPROP 1 LAST HDL_TAP TRUE
J 0
(-5750 2825);
DISPLAY 0.872340 (-5750 2825);
DISPLAY INVISIBLE (-5750 2825);
FORCEPROP 1 LAST PATH I215
J 0
(-6077 2950);
DISPLAY 0.872340 (-6077 2950);
PAINT GREEN (-6077 2950);
DISPLAY INVISIBLE (-6077 2950);
FORCEADD TAP..1
(-6075 2900);
FORCEPROP 3 LASTPIN (-6125 2900) SIG_NAME M_D_CPU0_SB_DQ<11>
J 0
(-6115 2910);
DISPLAY 0.659574 (-6115 2910);
PAINT MONO (-6115 2910);
DISPLAY INVISIBLE (-6115 2910);
FORCEPROP 1 LASTPIN (-6125 2900) BN 11
J 0
(-6137 2908);
DISPLAY 0.489362 (-6137 2908);
PAINT GREEN (-6137 2908);
FORCEPROP 2 LAST CDS_LIB mstr_standard
J 0
(-6075 2900);
DISPLAY 0.723404 (-6075 2900);
PAINT MONO (-6075 2900);
DISPLAY INVISIBLE (-6075 2900);
FORCEPROP 1 LAST BODY_TYPE PLUMBING
J 0
(-6075 2950);
DISPLAY 0.872340 (-6075 2950);
PAINT GREEN (-6075 2950);
DISPLAY INVISIBLE (-6075 2950);
FORCEPROP 1 LAST HDL_TAP TRUE
J 0
(-5750 2775);
DISPLAY 0.872340 (-5750 2775);
DISPLAY INVISIBLE (-5750 2775);
FORCEPROP 1 LAST PATH I216
J 0
(-6077 2900);
DISPLAY 0.872340 (-6077 2900);
PAINT GREEN (-6077 2900);
DISPLAY INVISIBLE (-6077 2900);
FORCEADD TAP..1
(-6075 3100);
FORCEPROP 3 LASTPIN (-6125 3100) SIG_NAME M_D_CPU0_SB_DQ<15>
J 0
(-6115 3110);
DISPLAY 0.659574 (-6115 3110);
PAINT MONO (-6115 3110);
DISPLAY INVISIBLE (-6115 3110);
FORCEPROP 1 LASTPIN (-6125 3100) BN 15
J 0
(-6137 3108);
DISPLAY 0.489362 (-6137 3108);
PAINT GREEN (-6137 3108);
FORCEPROP 2 LAST CDS_LIB mstr_standard
J 0
(-6075 3100);
DISPLAY 0.723404 (-6075 3100);
PAINT MONO (-6075 3100);
DISPLAY INVISIBLE (-6075 3100);
FORCEPROP 1 LAST BODY_TYPE PLUMBING
J 0
(-6075 3150);
DISPLAY 0.872340 (-6075 3150);
PAINT GREEN (-6075 3150);
DISPLAY INVISIBLE (-6075 3150);
FORCEPROP 1 LAST HDL_TAP TRUE
J 0
(-5750 2975);
DISPLAY 0.872340 (-5750 2975);
DISPLAY INVISIBLE (-5750 2975);
FORCEPROP 1 LAST PATH I217
J 0
(-6077 3100);
DISPLAY 0.872340 (-6077 3100);
PAINT GREEN (-6077 3100);
DISPLAY INVISIBLE (-6077 3100);
FORCEADD TAP..1
(-6075 3050);
FORCEPROP 3 LASTPIN (-6125 3050) SIG_NAME M_D_CPU0_SB_DQ<14>
J 0
(-6115 3060);
DISPLAY 0.659574 (-6115 3060);
PAINT MONO (-6115 3060);
DISPLAY INVISIBLE (-6115 3060);
FORCEPROP 1 LASTPIN (-6125 3050) BN 14
J 0
(-6137 3058);
DISPLAY 0.489362 (-6137 3058);
PAINT GREEN (-6137 3058);
FORCEPROP 2 LAST CDS_LIB mstr_standard
J 0
(-6075 3050);
DISPLAY 0.723404 (-6075 3050);
PAINT MONO (-6075 3050);
DISPLAY INVISIBLE (-6075 3050);
FORCEPROP 1 LAST BODY_TYPE PLUMBING
J 0
(-6075 3100);
DISPLAY 0.872340 (-6075 3100);
PAINT GREEN (-6075 3100);
DISPLAY INVISIBLE (-6075 3100);
FORCEPROP 1 LAST HDL_TAP TRUE
J 0
(-5750 2925);
DISPLAY 0.872340 (-5750 2925);
DISPLAY INVISIBLE (-5750 2925);
FORCEPROP 1 LAST PATH I218
J 0
(-6077 3050);
DISPLAY 0.872340 (-6077 3050);
PAINT GREEN (-6077 3050);
DISPLAY INVISIBLE (-6077 3050);
FORCEADD TAP..1
(-6075 3000);
FORCEPROP 3 LASTPIN (-6125 3000) SIG_NAME M_D_CPU0_SB_DQ<13>
J 0
(-6115 3010);
DISPLAY 0.659574 (-6115 3010);
PAINT MONO (-6115 3010);
DISPLAY INVISIBLE (-6115 3010);
FORCEPROP 1 LASTPIN (-6125 3000) BN 13
J 0
(-6137 3008);
DISPLAY 0.489362 (-6137 3008);
PAINT GREEN (-6137 3008);
FORCEPROP 2 LAST CDS_LIB mstr_standard
J 0
(-6075 3000);
DISPLAY 0.723404 (-6075 3000);
PAINT MONO (-6075 3000);
DISPLAY INVISIBLE (-6075 3000);
FORCEPROP 1 LAST BODY_TYPE PLUMBING
J 0
(-6075 3050);
DISPLAY 0.872340 (-6075 3050);
PAINT GREEN (-6075 3050);
DISPLAY INVISIBLE (-6075 3050);
FORCEPROP 1 LAST HDL_TAP TRUE
J 0
(-5750 2875);
DISPLAY 0.872340 (-5750 2875);
DISPLAY INVISIBLE (-5750 2875);
FORCEPROP 1 LAST PATH I219
J 0
(-6077 3000);
DISPLAY 0.872340 (-6077 3000);
PAINT GREEN (-6077 3000);
DISPLAY INVISIBLE (-6077 3000);
FORCEADD TAP..1
(-6075 3250);
FORCEPROP 3 LASTPIN (-6125 3250) SIG_NAME M_D_CPU0_SB_DQ<18>
J 0
(-6115 3260);
DISPLAY 0.659574 (-6115 3260);
PAINT MONO (-6115 3260);
DISPLAY INVISIBLE (-6115 3260);
FORCEPROP 1 LASTPIN (-6125 3250) BN 18
J 0
(-6137 3258);
DISPLAY 0.489362 (-6137 3258);
PAINT GREEN (-6137 3258);
FORCEPROP 2 LAST CDS_LIB mstr_standard
J 0
(-6075 3250);
DISPLAY 0.723404 (-6075 3250);
PAINT MONO (-6075 3250);
DISPLAY INVISIBLE (-6075 3250);
FORCEPROP 1 LAST BODY_TYPE PLUMBING
J 0
(-6075 3300);
DISPLAY 0.872340 (-6075 3300);
PAINT GREEN (-6075 3300);
DISPLAY INVISIBLE (-6075 3300);
FORCEPROP 1 LAST HDL_TAP TRUE
J 0
(-5750 3125);
DISPLAY 0.872340 (-5750 3125);
DISPLAY INVISIBLE (-5750 3125);
FORCEPROP 1 LAST PATH I220
J 0
(-6077 3250);
DISPLAY 0.872340 (-6077 3250);
PAINT GREEN (-6077 3250);
DISPLAY INVISIBLE (-6077 3250);
FORCEADD TAP..1
(-6075 3200);
FORCEPROP 3 LASTPIN (-6125 3200) SIG_NAME M_D_CPU0_SB_DQ<17>
J 0
(-6115 3210);
DISPLAY 0.659574 (-6115 3210);
PAINT MONO (-6115 3210);
DISPLAY INVISIBLE (-6115 3210);
FORCEPROP 1 LASTPIN (-6125 3200) BN 17
J 0
(-6137 3208);
DISPLAY 0.489362 (-6137 3208);
PAINT GREEN (-6137 3208);
FORCEPROP 2 LAST CDS_LIB mstr_standard
J 0
(-6075 3200);
DISPLAY 0.723404 (-6075 3200);
PAINT MONO (-6075 3200);
DISPLAY INVISIBLE (-6075 3200);
FORCEPROP 1 LAST BODY_TYPE PLUMBING
J 0
(-6075 3250);
DISPLAY 0.872340 (-6075 3250);
PAINT GREEN (-6075 3250);
DISPLAY INVISIBLE (-6075 3250);
FORCEPROP 1 LAST HDL_TAP TRUE
J 0
(-5750 3075);
DISPLAY 0.872340 (-5750 3075);
DISPLAY INVISIBLE (-5750 3075);
FORCEPROP 1 LAST PATH I221
J 0
(-6077 3200);
DISPLAY 0.872340 (-6077 3200);
PAINT GREEN (-6077 3200);
DISPLAY INVISIBLE (-6077 3200);
FORCEADD TAP..1
(-6075 3150);
FORCEPROP 3 LASTPIN (-6125 3150) SIG_NAME M_D_CPU0_SB_DQ<16>
J 0
(-6115 3160);
DISPLAY 0.659574 (-6115 3160);
PAINT MONO (-6115 3160);
DISPLAY INVISIBLE (-6115 3160);
FORCEPROP 1 LASTPIN (-6125 3150) BN 16
J 0
(-6137 3158);
DISPLAY 0.489362 (-6137 3158);
PAINT GREEN (-6137 3158);
FORCEPROP 2 LAST CDS_LIB mstr_standard
J 0
(-6075 3150);
DISPLAY 0.723404 (-6075 3150);
PAINT MONO (-6075 3150);
DISPLAY INVISIBLE (-6075 3150);
FORCEPROP 1 LAST BODY_TYPE PLUMBING
J 0
(-6075 3200);
DISPLAY 0.872340 (-6075 3200);
PAINT GREEN (-6075 3200);
DISPLAY INVISIBLE (-6075 3200);
FORCEPROP 1 LAST HDL_TAP TRUE
J 0
(-5750 3025);
DISPLAY 0.872340 (-5750 3025);
DISPLAY INVISIBLE (-5750 3025);
FORCEPROP 1 LAST PATH I222
J 0
(-6077 3150);
DISPLAY 0.872340 (-6077 3150);
PAINT GREEN (-6077 3150);
DISPLAY INVISIBLE (-6077 3150);
FORCEADD TAP..1
(-6075 3350);
FORCEPROP 3 LASTPIN (-6125 3350) SIG_NAME M_D_CPU0_SB_DQ<20>
J 0
(-6115 3360);
DISPLAY 0.659574 (-6115 3360);
PAINT MONO (-6115 3360);
DISPLAY INVISIBLE (-6115 3360);
FORCEPROP 1 LASTPIN (-6125 3350) BN 20
J 0
(-6137 3358);
DISPLAY 0.489362 (-6137 3358);
PAINT GREEN (-6137 3358);
FORCEPROP 2 LAST CDS_LIB mstr_standard
J 0
(-6075 3350);
DISPLAY 0.723404 (-6075 3350);
PAINT MONO (-6075 3350);
DISPLAY INVISIBLE (-6075 3350);
FORCEPROP 1 LAST BODY_TYPE PLUMBING
J 0
(-6075 3400);
DISPLAY 0.872340 (-6075 3400);
PAINT GREEN (-6075 3400);
DISPLAY INVISIBLE (-6075 3400);
FORCEPROP 1 LAST HDL_TAP TRUE
J 0
(-5750 3225);
DISPLAY 0.872340 (-5750 3225);
DISPLAY INVISIBLE (-5750 3225);
FORCEPROP 1 LAST PATH I223
J 0
(-6077 3350);
DISPLAY 0.872340 (-6077 3350);
PAINT GREEN (-6077 3350);
DISPLAY INVISIBLE (-6077 3350);
FORCEADD TAP..1
(-6075 3300);
FORCEPROP 3 LASTPIN (-6125 3300) SIG_NAME M_D_CPU0_SB_DQ<19>
J 0
(-6115 3310);
DISPLAY 0.659574 (-6115 3310);
PAINT MONO (-6115 3310);
DISPLAY INVISIBLE (-6115 3310);
FORCEPROP 1 LASTPIN (-6125 3300) BN 19
J 0
(-6137 3308);
DISPLAY 0.489362 (-6137 3308);
PAINT GREEN (-6137 3308);
FORCEPROP 2 LAST CDS_LIB mstr_standard
J 0
(-6075 3300);
DISPLAY 0.723404 (-6075 3300);
PAINT MONO (-6075 3300);
DISPLAY INVISIBLE (-6075 3300);
FORCEPROP 1 LAST BODY_TYPE PLUMBING
J 0
(-6075 3350);
DISPLAY 0.872340 (-6075 3350);
PAINT GREEN (-6075 3350);
DISPLAY INVISIBLE (-6075 3350);
FORCEPROP 1 LAST HDL_TAP TRUE
J 0
(-5750 3175);
DISPLAY 0.872340 (-5750 3175);
DISPLAY INVISIBLE (-5750 3175);
FORCEPROP 1 LAST PATH I224
J 0
(-6077 3300);
DISPLAY 0.872340 (-6077 3300);
PAINT GREEN (-6077 3300);
DISPLAY INVISIBLE (-6077 3300);
FORCEADD TAP..1
(-6075 3400);
FORCEPROP 3 LASTPIN (-6125 3400) SIG_NAME M_D_CPU0_SB_DQ<21>
J 0
(-6115 3410);
DISPLAY 0.659574 (-6115 3410);
PAINT MONO (-6115 3410);
DISPLAY INVISIBLE (-6115 3410);
FORCEPROP 1 LASTPIN (-6125 3400) BN 21
J 0
(-6137 3408);
DISPLAY 0.489362 (-6137 3408);
PAINT GREEN (-6137 3408);
FORCEPROP 2 LAST CDS_LIB mstr_standard
J 0
(-6075 3400);
DISPLAY 0.723404 (-6075 3400);
PAINT MONO (-6075 3400);
DISPLAY INVISIBLE (-6075 3400);
FORCEPROP 1 LAST BODY_TYPE PLUMBING
J 0
(-6075 3450);
DISPLAY 0.872340 (-6075 3450);
PAINT GREEN (-6075 3450);
DISPLAY INVISIBLE (-6075 3450);
FORCEPROP 1 LAST HDL_TAP TRUE
J 0
(-5750 3275);
DISPLAY 0.872340 (-5750 3275);
DISPLAY INVISIBLE (-5750 3275);
FORCEPROP 1 LAST PATH I225
J 0
(-6077 3400);
DISPLAY 0.872340 (-6077 3400);
PAINT GREEN (-6077 3400);
DISPLAY INVISIBLE (-6077 3400);
FORCEADD TAP..1
(-6075 3450);
FORCEPROP 3 LASTPIN (-6125 3450) SIG_NAME M_D_CPU0_SB_DQ<22>
J 0
(-6115 3460);
DISPLAY 0.659574 (-6115 3460);
PAINT MONO (-6115 3460);
DISPLAY INVISIBLE (-6115 3460);
FORCEPROP 1 LASTPIN (-6125 3450) BN 22
J 0
(-6137 3458);
DISPLAY 0.489362 (-6137 3458);
PAINT GREEN (-6137 3458);
FORCEPROP 2 LAST CDS_LIB mstr_standard
J 0
(-6075 3450);
DISPLAY 0.723404 (-6075 3450);
PAINT MONO (-6075 3450);
DISPLAY INVISIBLE (-6075 3450);
FORCEPROP 1 LAST BODY_TYPE PLUMBING
J 0
(-6075 3500);
DISPLAY 0.872340 (-6075 3500);
PAINT GREEN (-6075 3500);
DISPLAY INVISIBLE (-6075 3500);
FORCEPROP 1 LAST HDL_TAP TRUE
J 0
(-5750 3325);
DISPLAY 0.872340 (-5750 3325);
DISPLAY INVISIBLE (-5750 3325);
FORCEPROP 1 LAST PATH I226
J 0
(-6077 3450);
DISPLAY 0.872340 (-6077 3450);
PAINT GREEN (-6077 3450);
DISPLAY INVISIBLE (-6077 3450);
FORCEADD TAP..1
(-6075 3500);
FORCEPROP 3 LASTPIN (-6125 3500) SIG_NAME M_D_CPU0_SB_DQ<23>
J 0
(-6115 3510);
DISPLAY 0.659574 (-6115 3510);
PAINT MONO (-6115 3510);
DISPLAY INVISIBLE (-6115 3510);
FORCEPROP 1 LASTPIN (-6125 3500) BN 23
J 0
(-6137 3508);
DISPLAY 0.489362 (-6137 3508);
PAINT GREEN (-6137 3508);
FORCEPROP 2 LAST CDS_LIB mstr_standard
J 0
(-6075 3500);
DISPLAY 0.723404 (-6075 3500);
PAINT MONO (-6075 3500);
DISPLAY INVISIBLE (-6075 3500);
FORCEPROP 1 LAST BODY_TYPE PLUMBING
J 0
(-6075 3550);
DISPLAY 0.872340 (-6075 3550);
PAINT GREEN (-6075 3550);
DISPLAY INVISIBLE (-6075 3550);
FORCEPROP 1 LAST HDL_TAP TRUE
J 0
(-5750 3375);
DISPLAY 0.872340 (-5750 3375);
DISPLAY INVISIBLE (-5750 3375);
FORCEPROP 1 LAST PATH I227
J 0
(-6077 3500);
DISPLAY 0.872340 (-6077 3500);
PAINT GREEN (-6077 3500);
DISPLAY INVISIBLE (-6077 3500);
FORCEADD TAP..1
(-6075 3550);
FORCEPROP 3 LASTPIN (-6125 3550) SIG_NAME M_D_CPU0_SB_DQ<24>
J 0
(-6115 3560);
DISPLAY 0.659574 (-6115 3560);
PAINT MONO (-6115 3560);
DISPLAY INVISIBLE (-6115 3560);
FORCEPROP 1 LASTPIN (-6125 3550) BN 24
J 0
(-6137 3558);
DISPLAY 0.489362 (-6137 3558);
PAINT GREEN (-6137 3558);
FORCEPROP 2 LAST CDS_LIB mstr_standard
J 0
(-6075 3550);
DISPLAY 0.723404 (-6075 3550);
PAINT MONO (-6075 3550);
DISPLAY INVISIBLE (-6075 3550);
FORCEPROP 1 LAST BODY_TYPE PLUMBING
J 0
(-6075 3600);
DISPLAY 0.872340 (-6075 3600);
PAINT GREEN (-6075 3600);
DISPLAY INVISIBLE (-6075 3600);
FORCEPROP 1 LAST HDL_TAP TRUE
J 0
(-5750 3425);
DISPLAY 0.872340 (-5750 3425);
DISPLAY INVISIBLE (-5750 3425);
FORCEPROP 1 LAST PATH I228
J 0
(-6077 3550);
DISPLAY 0.872340 (-6077 3550);
PAINT GREEN (-6077 3550);
DISPLAY INVISIBLE (-6077 3550);
FORCEADD TAP..1
(-6075 3600);
FORCEPROP 3 LASTPIN (-6125 3600) SIG_NAME M_D_CPU0_SB_DQ<25>
J 0
(-6115 3610);
DISPLAY 0.659574 (-6115 3610);
PAINT MONO (-6115 3610);
DISPLAY INVISIBLE (-6115 3610);
FORCEPROP 1 LASTPIN (-6125 3600) BN 25
J 0
(-6137 3608);
DISPLAY 0.489362 (-6137 3608);
PAINT GREEN (-6137 3608);
FORCEPROP 2 LAST CDS_LIB mstr_standard
J 0
(-6075 3600);
DISPLAY 0.723404 (-6075 3600);
PAINT MONO (-6075 3600);
DISPLAY INVISIBLE (-6075 3600);
FORCEPROP 1 LAST BODY_TYPE PLUMBING
J 0
(-6075 3650);
DISPLAY 0.872340 (-6075 3650);
PAINT GREEN (-6075 3650);
DISPLAY INVISIBLE (-6075 3650);
FORCEPROP 1 LAST HDL_TAP TRUE
J 0
(-5750 3475);
DISPLAY 0.872340 (-5750 3475);
DISPLAY INVISIBLE (-5750 3475);
FORCEPROP 1 LAST PATH I229
J 0
(-6077 3600);
DISPLAY 0.872340 (-6077 3600);
PAINT GREEN (-6077 3600);
DISPLAY INVISIBLE (-6077 3600);
FORCEADD TAP..1
(-6075 3650);
FORCEPROP 3 LASTPIN (-6125 3650) SIG_NAME M_D_CPU0_SB_DQ<26>
J 0
(-6115 3660);
DISPLAY 0.659574 (-6115 3660);
PAINT MONO (-6115 3660);
DISPLAY INVISIBLE (-6115 3660);
FORCEPROP 1 LASTPIN (-6125 3650) BN 26
J 0
(-6137 3658);
DISPLAY 0.489362 (-6137 3658);
PAINT GREEN (-6137 3658);
FORCEPROP 2 LAST CDS_LIB mstr_standard
J 0
(-6075 3650);
DISPLAY 0.723404 (-6075 3650);
PAINT MONO (-6075 3650);
DISPLAY INVISIBLE (-6075 3650);
FORCEPROP 1 LAST BODY_TYPE PLUMBING
J 0
(-6075 3700);
DISPLAY 0.872340 (-6075 3700);
PAINT GREEN (-6075 3700);
DISPLAY INVISIBLE (-6075 3700);
FORCEPROP 1 LAST HDL_TAP TRUE
J 0
(-5750 3525);
DISPLAY 0.872340 (-5750 3525);
DISPLAY INVISIBLE (-5750 3525);
FORCEPROP 1 LAST PATH I230
J 0
(-6077 3650);
DISPLAY 0.872340 (-6077 3650);
PAINT GREEN (-6077 3650);
DISPLAY INVISIBLE (-6077 3650);
FORCEADD TAP..1
(-6075 3700);
FORCEPROP 3 LASTPIN (-6125 3700) SIG_NAME M_D_CPU0_SB_DQ<27>
J 0
(-6115 3710);
DISPLAY 0.659574 (-6115 3710);
PAINT MONO (-6115 3710);
DISPLAY INVISIBLE (-6115 3710);
FORCEPROP 1 LASTPIN (-6125 3700) BN 27
J 0
(-6137 3708);
DISPLAY 0.489362 (-6137 3708);
PAINT GREEN (-6137 3708);
FORCEPROP 2 LAST CDS_LIB mstr_standard
J 0
(-6075 3700);
DISPLAY 0.723404 (-6075 3700);
PAINT MONO (-6075 3700);
DISPLAY INVISIBLE (-6075 3700);
FORCEPROP 1 LAST BODY_TYPE PLUMBING
J 0
(-6075 3750);
DISPLAY 0.872340 (-6075 3750);
PAINT GREEN (-6075 3750);
DISPLAY INVISIBLE (-6075 3750);
FORCEPROP 1 LAST HDL_TAP TRUE
J 0
(-5750 3575);
DISPLAY 0.872340 (-5750 3575);
DISPLAY INVISIBLE (-5750 3575);
FORCEPROP 1 LAST PATH I231
J 0
(-6077 3700);
DISPLAY 0.872340 (-6077 3700);
PAINT GREEN (-6077 3700);
DISPLAY INVISIBLE (-6077 3700);
FORCEADD TAP..1
(-6075 3750);
FORCEPROP 3 LASTPIN (-6125 3750) SIG_NAME M_D_CPU0_SB_DQ<28>
J 0
(-6115 3760);
DISPLAY 0.659574 (-6115 3760);
PAINT MONO (-6115 3760);
DISPLAY INVISIBLE (-6115 3760);
FORCEPROP 1 LASTPIN (-6125 3750) BN 28
J 0
(-6137 3758);
DISPLAY 0.489362 (-6137 3758);
PAINT GREEN (-6137 3758);
FORCEPROP 2 LAST CDS_LIB mstr_standard
J 0
(-6075 3750);
DISPLAY 0.723404 (-6075 3750);
PAINT MONO (-6075 3750);
DISPLAY INVISIBLE (-6075 3750);
FORCEPROP 1 LAST BODY_TYPE PLUMBING
J 0
(-6075 3800);
DISPLAY 0.872340 (-6075 3800);
PAINT GREEN (-6075 3800);
DISPLAY INVISIBLE (-6075 3800);
FORCEPROP 1 LAST HDL_TAP TRUE
J 0
(-5750 3625);
DISPLAY 0.872340 (-5750 3625);
DISPLAY INVISIBLE (-5750 3625);
FORCEPROP 1 LAST PATH I232
J 0
(-6077 3750);
DISPLAY 0.872340 (-6077 3750);
PAINT GREEN (-6077 3750);
DISPLAY INVISIBLE (-6077 3750);
FORCEADD TAP..1
(-6075 3800);
FORCEPROP 3 LASTPIN (-6125 3800) SIG_NAME M_D_CPU0_SB_DQ<29>
J 0
(-6115 3810);
DISPLAY 0.659574 (-6115 3810);
PAINT MONO (-6115 3810);
DISPLAY INVISIBLE (-6115 3810);
FORCEPROP 1 LASTPIN (-6125 3800) BN 29
J 0
(-6137 3808);
DISPLAY 0.489362 (-6137 3808);
PAINT GREEN (-6137 3808);
FORCEPROP 2 LAST CDS_LIB mstr_standard
J 0
(-6075 3800);
DISPLAY 0.723404 (-6075 3800);
PAINT MONO (-6075 3800);
DISPLAY INVISIBLE (-6075 3800);
FORCEPROP 1 LAST BODY_TYPE PLUMBING
J 0
(-6075 3850);
DISPLAY 0.872340 (-6075 3850);
PAINT GREEN (-6075 3850);
DISPLAY INVISIBLE (-6075 3850);
FORCEPROP 1 LAST HDL_TAP TRUE
J 0
(-5750 3675);
DISPLAY 0.872340 (-5750 3675);
DISPLAY INVISIBLE (-5750 3675);
FORCEPROP 1 LAST PATH I233
J 0
(-6077 3800);
DISPLAY 0.872340 (-6077 3800);
PAINT GREEN (-6077 3800);
DISPLAY INVISIBLE (-6077 3800);
FORCEADD TAP..1
(-6075 3850);
FORCEPROP 3 LASTPIN (-6125 3850) SIG_NAME M_D_CPU0_SB_DQ<30>
J 0
(-6115 3860);
DISPLAY 0.659574 (-6115 3860);
PAINT MONO (-6115 3860);
DISPLAY INVISIBLE (-6115 3860);
FORCEPROP 1 LASTPIN (-6125 3850) BN 30
J 0
(-6137 3858);
DISPLAY 0.489362 (-6137 3858);
PAINT GREEN (-6137 3858);
FORCEPROP 2 LAST CDS_LIB mstr_standard
J 0
(-6075 3850);
DISPLAY 0.723404 (-6075 3850);
PAINT MONO (-6075 3850);
DISPLAY INVISIBLE (-6075 3850);
FORCEPROP 1 LAST BODY_TYPE PLUMBING
J 0
(-6075 3900);
DISPLAY 0.872340 (-6075 3900);
PAINT GREEN (-6075 3900);
DISPLAY INVISIBLE (-6075 3900);
FORCEPROP 1 LAST HDL_TAP TRUE
J 0
(-5750 3725);
DISPLAY 0.872340 (-5750 3725);
DISPLAY INVISIBLE (-5750 3725);
FORCEPROP 1 LAST PATH I234
J 0
(-6077 3850);
DISPLAY 0.872340 (-6077 3850);
PAINT GREEN (-6077 3850);
DISPLAY INVISIBLE (-6077 3850);
FORCEADD TAP..1
(-6075 4000);
FORCEPROP 3 LASTPIN (-6125 4000) SIG_NAME M_D_CPU0_SA_DQ<0>
J 0
(-6115 4010);
DISPLAY 0.659574 (-6115 4010);
PAINT MONO (-6115 4010);
DISPLAY INVISIBLE (-6115 4010);
FORCEPROP 1 LASTPIN (-6125 4000) BN 0
J 0
(-6137 4008);
DISPLAY 0.489362 (-6137 4008);
PAINT GREEN (-6137 4008);
FORCEPROP 2 LAST CDS_LIB mstr_standard
J 0
(-6075 4000);
DISPLAY 0.723404 (-6075 4000);
PAINT MONO (-6075 4000);
DISPLAY INVISIBLE (-6075 4000);
FORCEPROP 1 LAST BODY_TYPE PLUMBING
J 0
(-6075 4050);
DISPLAY 0.872340 (-6075 4050);
PAINT GREEN (-6075 4050);
DISPLAY INVISIBLE (-6075 4050);
FORCEPROP 1 LAST HDL_TAP TRUE
J 0
(-5750 3875);
DISPLAY 0.872340 (-5750 3875);
DISPLAY INVISIBLE (-5750 3875);
FORCEPROP 1 LAST PATH I235
J 0
(-6077 4000);
DISPLAY 0.872340 (-6077 4000);
PAINT GREEN (-6077 4000);
DISPLAY INVISIBLE (-6077 4000);
FORCEADD TAP..1
(-6075 3900);
FORCEPROP 3 LASTPIN (-6125 3900) SIG_NAME M_D_CPU0_SB_DQ<31>
J 0
(-6115 3910);
DISPLAY 0.659574 (-6115 3910);
PAINT MONO (-6115 3910);
DISPLAY INVISIBLE (-6115 3910);
FORCEPROP 1 LASTPIN (-6125 3900) BN 31
J 0
(-6137 3908);
DISPLAY 0.489362 (-6137 3908);
PAINT GREEN (-6137 3908);
FORCEPROP 2 LAST CDS_LIB mstr_standard
J 0
(-6075 3900);
DISPLAY 0.723404 (-6075 3900);
PAINT MONO (-6075 3900);
DISPLAY INVISIBLE (-6075 3900);
FORCEPROP 1 LAST BODY_TYPE PLUMBING
J 0
(-6075 3950);
DISPLAY 0.872340 (-6075 3950);
PAINT GREEN (-6075 3950);
DISPLAY INVISIBLE (-6075 3950);
FORCEPROP 1 LAST HDL_TAP TRUE
J 0
(-5750 3775);
DISPLAY 0.872340 (-5750 3775);
DISPLAY INVISIBLE (-5750 3775);
FORCEPROP 1 LAST PATH I236
J 0
(-6077 3900);
DISPLAY 0.872340 (-6077 3900);
PAINT GREEN (-6077 3900);
DISPLAY INVISIBLE (-6077 3900);
FORCEADD TAP..1
(-6075 4050);
FORCEPROP 3 LASTPIN (-6125 4050) SIG_NAME M_D_CPU0_SA_DQ<1>
J 0
(-6115 4060);
DISPLAY 0.659574 (-6115 4060);
PAINT MONO (-6115 4060);
DISPLAY INVISIBLE (-6115 4060);
FORCEPROP 1 LASTPIN (-6125 4050) BN 1
J 0
(-6137 4058);
DISPLAY 0.489362 (-6137 4058);
PAINT GREEN (-6137 4058);
FORCEPROP 2 LAST CDS_LIB mstr_standard
J 0
(-6075 4050);
DISPLAY 0.723404 (-6075 4050);
PAINT MONO (-6075 4050);
DISPLAY INVISIBLE (-6075 4050);
FORCEPROP 1 LAST BODY_TYPE PLUMBING
J 0
(-6075 4100);
DISPLAY 0.872340 (-6075 4100);
PAINT GREEN (-6075 4100);
DISPLAY INVISIBLE (-6075 4100);
FORCEPROP 1 LAST HDL_TAP TRUE
J 0
(-5750 3925);
DISPLAY 0.872340 (-5750 3925);
DISPLAY INVISIBLE (-5750 3925);
FORCEPROP 1 LAST PATH I237
J 0
(-6077 4050);
DISPLAY 0.872340 (-6077 4050);
PAINT GREEN (-6077 4050);
DISPLAY INVISIBLE (-6077 4050);
FORCEADD TAP..1
(-6075 4100);
FORCEPROP 3 LASTPIN (-6125 4100) SIG_NAME M_D_CPU0_SA_DQ<2>
J 0
(-6115 4110);
DISPLAY 0.659574 (-6115 4110);
PAINT MONO (-6115 4110);
DISPLAY INVISIBLE (-6115 4110);
FORCEPROP 1 LASTPIN (-6125 4100) BN 2
J 0
(-6137 4108);
DISPLAY 0.489362 (-6137 4108);
PAINT GREEN (-6137 4108);
FORCEPROP 2 LAST CDS_LIB mstr_standard
J 0
(-6075 4100);
DISPLAY 0.723404 (-6075 4100);
PAINT MONO (-6075 4100);
DISPLAY INVISIBLE (-6075 4100);
FORCEPROP 1 LAST BODY_TYPE PLUMBING
J 0
(-6075 4150);
DISPLAY 0.872340 (-6075 4150);
PAINT GREEN (-6075 4150);
DISPLAY INVISIBLE (-6075 4150);
FORCEPROP 1 LAST HDL_TAP TRUE
J 0
(-5750 3975);
DISPLAY 0.872340 (-5750 3975);
DISPLAY INVISIBLE (-5750 3975);
FORCEPROP 1 LAST PATH I238
J 0
(-6077 4100);
DISPLAY 0.872340 (-6077 4100);
PAINT GREEN (-6077 4100);
DISPLAY INVISIBLE (-6077 4100);
FORCEADD TAP..1
R 2
(-7775 4150);
FORCEPROP 3 LASTPIN (-7725 4150) SIG_NAME M_D_CPU0_SA_CB<7>
J 0
(-7715 4160);
DISPLAY 0.659574 (-7715 4160);
PAINT MONO (-7715 4160);
DISPLAY INVISIBLE (-7715 4160);
FORCEPROP 1 LASTPIN (-7725 4150) BN 7
J 2
(-7713 4158);
DISPLAY 0.489362 (-7713 4158);
PAINT GREEN (-7713 4158);
FORCEPROP 2 LAST CDS_LIB mstr_standard
J 0
(-7775 4150);
DISPLAY 0.723404 (-7775 4150);
PAINT MONO (-7775 4150);
DISPLAY INVISIBLE (-7775 4150);
FORCEPROP 1 LAST BODY_TYPE PLUMBING
J 2
(-7775 4200);
DISPLAY 0.872340 (-7775 4200);
PAINT GREEN (-7775 4200);
DISPLAY INVISIBLE (-7775 4200);
FORCEPROP 1 LAST HDL_TAP TRUE
J 2
(-8100 4025);
DISPLAY 0.872340 (-8100 4025);
DISPLAY INVISIBLE (-8100 4025);
FORCEPROP 1 LAST PATH I239
J 2
(-7773 4150);
DISPLAY 0.872340 (-7773 4150);
PAINT GREEN (-7773 4150);
DISPLAY INVISIBLE (-7773 4150);
FORCEADD TAP..1
R 2
(-7775 4850);
FORCEPROP 3 LASTPIN (-7725 4850) SIG_NAME M_D_CPU0_SB_CA<0>
J 0
(-7715 4860);
DISPLAY 0.659574 (-7715 4860);
PAINT MONO (-7715 4860);
DISPLAY INVISIBLE (-7715 4860);
FORCEPROP 1 LASTPIN (-7725 4850) BN 0
J 2
(-7713 4858);
DISPLAY 0.489362 (-7713 4858);
PAINT GREEN (-7713 4858);
FORCEPROP 2 LAST CDS_LIB mstr_standard
J 0
(-7775 4850);
DISPLAY 0.723404 (-7775 4850);
PAINT MONO (-7775 4850);
DISPLAY INVISIBLE (-7775 4850);
FORCEPROP 1 LAST BODY_TYPE PLUMBING
J 2
(-7775 4900);
DISPLAY 0.872340 (-7775 4900);
PAINT GREEN (-7775 4900);
DISPLAY INVISIBLE (-7775 4900);
FORCEPROP 1 LAST HDL_TAP TRUE
J 2
(-8100 4725);
DISPLAY 0.872340 (-8100 4725);
DISPLAY INVISIBLE (-8100 4725);
FORCEPROP 1 LAST PATH I240
J 2
(-7773 4850);
DISPLAY 0.872340 (-7773 4850);
PAINT GREEN (-7773 4850);
DISPLAY INVISIBLE (-7773 4850);
FORCEADD TAP..1
R 2
(-7775 4900);
FORCEPROP 3 LASTPIN (-7725 4900) SIG_NAME M_D_CPU0_SB_CA<1>
J 0
(-7715 4910);
DISPLAY 0.659574 (-7715 4910);
PAINT MONO (-7715 4910);
DISPLAY INVISIBLE (-7715 4910);
FORCEPROP 1 LASTPIN (-7725 4900) BN 1
J 2
(-7713 4908);
DISPLAY 0.489362 (-7713 4908);
PAINT GREEN (-7713 4908);
FORCEPROP 2 LAST CDS_LIB mstr_standard
J 0
(-7775 4900);
DISPLAY 0.723404 (-7775 4900);
PAINT MONO (-7775 4900);
DISPLAY INVISIBLE (-7775 4900);
FORCEPROP 1 LAST BODY_TYPE PLUMBING
J 2
(-7775 4950);
DISPLAY 0.872340 (-7775 4950);
PAINT GREEN (-7775 4950);
DISPLAY INVISIBLE (-7775 4950);
FORCEPROP 1 LAST HDL_TAP TRUE
J 2
(-8100 4775);
DISPLAY 0.872340 (-8100 4775);
DISPLAY INVISIBLE (-8100 4775);
FORCEPROP 1 LAST PATH I241
J 2
(-7773 4900);
DISPLAY 0.872340 (-7773 4900);
PAINT GREEN (-7773 4900);
DISPLAY INVISIBLE (-7773 4900);
FORCEADD TAP..1
R 2
(-7775 4950);
FORCEPROP 3 LASTPIN (-7725 4950) SIG_NAME M_D_CPU0_SB_CA<2>
J 0
(-7715 4960);
DISPLAY 0.659574 (-7715 4960);
PAINT MONO (-7715 4960);
DISPLAY INVISIBLE (-7715 4960);
FORCEPROP 1 LASTPIN (-7725 4950) BN 2
J 2
(-7713 4958);
DISPLAY 0.489362 (-7713 4958);
PAINT GREEN (-7713 4958);
FORCEPROP 2 LAST CDS_LIB mstr_standard
J 0
(-7775 4950);
DISPLAY 0.723404 (-7775 4950);
PAINT MONO (-7775 4950);
DISPLAY INVISIBLE (-7775 4950);
FORCEPROP 1 LAST BODY_TYPE PLUMBING
J 2
(-7775 5000);
DISPLAY 0.872340 (-7775 5000);
PAINT GREEN (-7775 5000);
DISPLAY INVISIBLE (-7775 5000);
FORCEPROP 1 LAST HDL_TAP TRUE
J 2
(-8100 4825);
DISPLAY 0.872340 (-8100 4825);
DISPLAY INVISIBLE (-8100 4825);
FORCEPROP 1 LAST PATH I242
J 2
(-7773 4950);
DISPLAY 0.872340 (-7773 4950);
PAINT GREEN (-7773 4950);
DISPLAY INVISIBLE (-7773 4950);
FORCEADD TAP..1
R 2
(-7775 5000);
FORCEPROP 3 LASTPIN (-7725 5000) SIG_NAME M_D_CPU0_SB_CA<3>
J 0
(-7715 5010);
DISPLAY 0.659574 (-7715 5010);
PAINT MONO (-7715 5010);
DISPLAY INVISIBLE (-7715 5010);
FORCEPROP 1 LASTPIN (-7725 5000) BN 3
J 2
(-7713 5008);
DISPLAY 0.489362 (-7713 5008);
PAINT GREEN (-7713 5008);
FORCEPROP 2 LAST CDS_LIB mstr_standard
J 0
(-7775 5000);
DISPLAY 0.723404 (-7775 5000);
PAINT MONO (-7775 5000);
DISPLAY INVISIBLE (-7775 5000);
FORCEPROP 1 LAST BODY_TYPE PLUMBING
J 2
(-7775 5050);
DISPLAY 0.872340 (-7775 5050);
PAINT GREEN (-7775 5050);
DISPLAY INVISIBLE (-7775 5050);
FORCEPROP 1 LAST HDL_TAP TRUE
J 2
(-8100 4875);
DISPLAY 0.872340 (-8100 4875);
DISPLAY INVISIBLE (-8100 4875);
FORCEPROP 1 LAST PATH I243
J 2
(-7773 5000);
DISPLAY 0.872340 (-7773 5000);
PAINT GREEN (-7773 5000);
DISPLAY INVISIBLE (-7773 5000);
FORCEADD TAP..1
R 2
(-7775 5050);
FORCEPROP 3 LASTPIN (-7725 5050) SIG_NAME M_D_CPU0_SB_CA<4>
J 0
(-7715 5060);
DISPLAY 0.659574 (-7715 5060);
PAINT MONO (-7715 5060);
DISPLAY INVISIBLE (-7715 5060);
FORCEPROP 1 LASTPIN (-7725 5050) BN 4
J 2
(-7713 5058);
DISPLAY 0.489362 (-7713 5058);
PAINT GREEN (-7713 5058);
FORCEPROP 2 LAST CDS_LIB mstr_standard
J 0
(-7775 5050);
DISPLAY 0.723404 (-7775 5050);
PAINT MONO (-7775 5050);
DISPLAY INVISIBLE (-7775 5050);
FORCEPROP 1 LAST BODY_TYPE PLUMBING
J 2
(-7775 5100);
DISPLAY 0.872340 (-7775 5100);
PAINT GREEN (-7775 5100);
DISPLAY INVISIBLE (-7775 5100);
FORCEPROP 1 LAST HDL_TAP TRUE
J 2
(-8100 4925);
DISPLAY 0.872340 (-8100 4925);
DISPLAY INVISIBLE (-8100 4925);
FORCEPROP 1 LAST PATH I244
J 2
(-7773 5050);
DISPLAY 0.872340 (-7773 5050);
PAINT GREEN (-7773 5050);
DISPLAY INVISIBLE (-7773 5050);
FORCEADD TAP..1
R 2
(-7775 5100);
FORCEPROP 3 LASTPIN (-7725 5100) SIG_NAME M_D_CPU0_SB_CA<5>
J 0
(-7715 5110);
DISPLAY 0.659574 (-7715 5110);
PAINT MONO (-7715 5110);
DISPLAY INVISIBLE (-7715 5110);
FORCEPROP 1 LASTPIN (-7725 5100) BN 5
J 2
(-7713 5108);
DISPLAY 0.489362 (-7713 5108);
PAINT GREEN (-7713 5108);
FORCEPROP 2 LAST CDS_LIB mstr_standard
J 0
(-7775 5100);
DISPLAY 0.723404 (-7775 5100);
PAINT MONO (-7775 5100);
DISPLAY INVISIBLE (-7775 5100);
FORCEPROP 1 LAST BODY_TYPE PLUMBING
J 2
(-7775 5150);
DISPLAY 0.872340 (-7775 5150);
PAINT GREEN (-7775 5150);
DISPLAY INVISIBLE (-7775 5150);
FORCEPROP 1 LAST HDL_TAP TRUE
J 2
(-8100 4975);
DISPLAY 0.872340 (-8100 4975);
DISPLAY INVISIBLE (-8100 4975);
FORCEPROP 1 LAST PATH I245
J 2
(-7773 5100);
DISPLAY 0.872340 (-7773 5100);
PAINT GREEN (-7773 5100);
DISPLAY INVISIBLE (-7773 5100);
FORCEADD TAP..1
R 2
(-7775 5150);
FORCEPROP 3 LASTPIN (-7725 5150) SIG_NAME M_D_CPU0_SB_CA<6>
J 0
(-7715 5160);
DISPLAY 0.659574 (-7715 5160);
PAINT MONO (-7715 5160);
DISPLAY INVISIBLE (-7715 5160);
FORCEPROP 1 LASTPIN (-7725 5150) BN 6
J 2
(-7713 5158);
DISPLAY 0.489362 (-7713 5158);
PAINT GREEN (-7713 5158);
FORCEPROP 2 LAST CDS_LIB mstr_standard
J 0
(-7775 5150);
DISPLAY 0.723404 (-7775 5150);
PAINT MONO (-7775 5150);
DISPLAY INVISIBLE (-7775 5150);
FORCEPROP 1 LAST BODY_TYPE PLUMBING
J 2
(-7775 5200);
DISPLAY 0.872340 (-7775 5200);
PAINT GREEN (-7775 5200);
DISPLAY INVISIBLE (-7775 5200);
FORCEPROP 1 LAST HDL_TAP TRUE
J 2
(-8100 5025);
DISPLAY 0.872340 (-8100 5025);
DISPLAY INVISIBLE (-8100 5025);
FORCEPROP 1 LAST PATH I246
J 2
(-7773 5150);
DISPLAY 0.872340 (-7773 5150);
PAINT GREEN (-7773 5150);
DISPLAY INVISIBLE (-7773 5150);
FORCEADD TAP..1
R 2
(-7775 5250);
FORCEPROP 3 LASTPIN (-7725 5250) SIG_NAME M_D_CPU0_SA_CA<0>
J 0
(-7715 5260);
DISPLAY 0.659574 (-7715 5260);
PAINT MONO (-7715 5260);
DISPLAY INVISIBLE (-7715 5260);
FORCEPROP 1 LASTPIN (-7725 5250) BN 0
J 2
(-7713 5258);
DISPLAY 0.489362 (-7713 5258);
PAINT GREEN (-7713 5258);
FORCEPROP 2 LAST CDS_LIB mstr_standard
J 0
(-7775 5250);
DISPLAY 0.723404 (-7775 5250);
PAINT MONO (-7775 5250);
DISPLAY INVISIBLE (-7775 5250);
FORCEPROP 1 LAST BODY_TYPE PLUMBING
J 2
(-7775 5300);
DISPLAY 0.872340 (-7775 5300);
PAINT GREEN (-7775 5300);
DISPLAY INVISIBLE (-7775 5300);
FORCEPROP 1 LAST HDL_TAP TRUE
J 2
(-8100 5125);
DISPLAY 0.872340 (-8100 5125);
DISPLAY INVISIBLE (-8100 5125);
FORCEPROP 1 LAST PATH I247
J 2
(-7773 5250);
DISPLAY 0.872340 (-7773 5250);
PAINT GREEN (-7773 5250);
DISPLAY INVISIBLE (-7773 5250);
FORCEADD TAP..1
R 2
(-7775 5300);
FORCEPROP 3 LASTPIN (-7725 5300) SIG_NAME M_D_CPU0_SA_CA<1>
J 0
(-7715 5310);
DISPLAY 0.659574 (-7715 5310);
PAINT MONO (-7715 5310);
DISPLAY INVISIBLE (-7715 5310);
FORCEPROP 1 LASTPIN (-7725 5300) BN 1
J 2
(-7713 5308);
DISPLAY 0.489362 (-7713 5308);
PAINT GREEN (-7713 5308);
FORCEPROP 2 LAST CDS_LIB mstr_standard
J 0
(-7775 5300);
DISPLAY 0.723404 (-7775 5300);
PAINT MONO (-7775 5300);
DISPLAY INVISIBLE (-7775 5300);
FORCEPROP 1 LAST BODY_TYPE PLUMBING
J 2
(-7775 5350);
DISPLAY 0.872340 (-7775 5350);
PAINT GREEN (-7775 5350);
DISPLAY INVISIBLE (-7775 5350);
FORCEPROP 1 LAST HDL_TAP TRUE
J 2
(-8100 5175);
DISPLAY 0.872340 (-8100 5175);
DISPLAY INVISIBLE (-8100 5175);
FORCEPROP 1 LAST PATH I248
J 2
(-7773 5300);
DISPLAY 0.872340 (-7773 5300);
PAINT GREEN (-7773 5300);
DISPLAY INVISIBLE (-7773 5300);
FORCEADD TAP..1
R 2
(-7775 5350);
FORCEPROP 3 LASTPIN (-7725 5350) SIG_NAME M_D_CPU0_SA_CA<2>
J 0
(-7715 5360);
DISPLAY 0.659574 (-7715 5360);
PAINT MONO (-7715 5360);
DISPLAY INVISIBLE (-7715 5360);
FORCEPROP 1 LASTPIN (-7725 5350) BN 2
J 2
(-7713 5358);
DISPLAY 0.489362 (-7713 5358);
PAINT GREEN (-7713 5358);
FORCEPROP 2 LAST CDS_LIB mstr_standard
J 0
(-7775 5350);
DISPLAY 0.723404 (-7775 5350);
PAINT MONO (-7775 5350);
DISPLAY INVISIBLE (-7775 5350);
FORCEPROP 1 LAST BODY_TYPE PLUMBING
J 2
(-7775 5400);
DISPLAY 0.872340 (-7775 5400);
PAINT GREEN (-7775 5400);
DISPLAY INVISIBLE (-7775 5400);
FORCEPROP 1 LAST HDL_TAP TRUE
J 2
(-8100 5225);
DISPLAY 0.872340 (-8100 5225);
DISPLAY INVISIBLE (-8100 5225);
FORCEPROP 1 LAST PATH I249
J 2
(-7773 5350);
DISPLAY 0.872340 (-7773 5350);
PAINT GREEN (-7773 5350);
DISPLAY INVISIBLE (-7773 5350);
FORCEADD TAP..1
R 2
(-7775 5400);
FORCEPROP 3 LASTPIN (-7725 5400) SIG_NAME M_D_CPU0_SA_CA<3>
J 0
(-7715 5410);
DISPLAY 0.659574 (-7715 5410);
PAINT MONO (-7715 5410);
DISPLAY INVISIBLE (-7715 5410);
FORCEPROP 1 LASTPIN (-7725 5400) BN 3
J 2
(-7713 5408);
DISPLAY 0.489362 (-7713 5408);
PAINT GREEN (-7713 5408);
FORCEPROP 2 LAST CDS_LIB mstr_standard
J 0
(-7775 5400);
DISPLAY 0.723404 (-7775 5400);
PAINT MONO (-7775 5400);
DISPLAY INVISIBLE (-7775 5400);
FORCEPROP 1 LAST BODY_TYPE PLUMBING
J 2
(-7775 5450);
DISPLAY 0.872340 (-7775 5450);
PAINT GREEN (-7775 5450);
DISPLAY INVISIBLE (-7775 5450);
FORCEPROP 1 LAST HDL_TAP TRUE
J 2
(-8100 5275);
DISPLAY 0.872340 (-8100 5275);
DISPLAY INVISIBLE (-8100 5275);
FORCEPROP 1 LAST PATH I250
J 2
(-7773 5400);
DISPLAY 0.872340 (-7773 5400);
PAINT GREEN (-7773 5400);
DISPLAY INVISIBLE (-7773 5400);
FORCEADD TAP..1
R 2
(-7775 5450);
FORCEPROP 3 LASTPIN (-7725 5450) SIG_NAME M_D_CPU0_SA_CA<4>
J 0
(-7715 5460);
DISPLAY 0.659574 (-7715 5460);
PAINT MONO (-7715 5460);
DISPLAY INVISIBLE (-7715 5460);
FORCEPROP 1 LASTPIN (-7725 5450) BN 4
J 2
(-7713 5458);
DISPLAY 0.489362 (-7713 5458);
PAINT GREEN (-7713 5458);
FORCEPROP 2 LAST CDS_LIB mstr_standard
J 0
(-7775 5450);
DISPLAY 0.723404 (-7775 5450);
PAINT MONO (-7775 5450);
DISPLAY INVISIBLE (-7775 5450);
FORCEPROP 1 LAST BODY_TYPE PLUMBING
J 2
(-7775 5500);
DISPLAY 0.872340 (-7775 5500);
PAINT GREEN (-7775 5500);
DISPLAY INVISIBLE (-7775 5500);
FORCEPROP 1 LAST HDL_TAP TRUE
J 2
(-8100 5325);
DISPLAY 0.872340 (-8100 5325);
DISPLAY INVISIBLE (-8100 5325);
FORCEPROP 1 LAST PATH I251
J 2
(-7773 5450);
DISPLAY 0.872340 (-7773 5450);
PAINT GREEN (-7773 5450);
DISPLAY INVISIBLE (-7773 5450);
FORCEADD TAP..1
R 2
(-7775 5500);
FORCEPROP 3 LASTPIN (-7725 5500) SIG_NAME M_D_CPU0_SA_CA<5>
J 0
(-7715 5510);
DISPLAY 0.659574 (-7715 5510);
PAINT MONO (-7715 5510);
DISPLAY INVISIBLE (-7715 5510);
FORCEPROP 1 LASTPIN (-7725 5500) BN 5
J 2
(-7713 5508);
DISPLAY 0.489362 (-7713 5508);
PAINT GREEN (-7713 5508);
FORCEPROP 2 LAST CDS_LIB mstr_standard
J 0
(-7775 5500);
DISPLAY 0.723404 (-7775 5500);
PAINT MONO (-7775 5500);
DISPLAY INVISIBLE (-7775 5500);
FORCEPROP 1 LAST BODY_TYPE PLUMBING
J 2
(-7775 5550);
DISPLAY 0.872340 (-7775 5550);
PAINT GREEN (-7775 5550);
DISPLAY INVISIBLE (-7775 5550);
FORCEPROP 1 LAST HDL_TAP TRUE
J 2
(-8100 5375);
DISPLAY 0.872340 (-8100 5375);
DISPLAY INVISIBLE (-8100 5375);
FORCEPROP 1 LAST PATH I252
J 2
(-7773 5500);
DISPLAY 0.872340 (-7773 5500);
PAINT GREEN (-7773 5500);
DISPLAY INVISIBLE (-7773 5500);
FORCEADD TAP..1
R 2
(-7775 5550);
FORCEPROP 3 LASTPIN (-7725 5550) SIG_NAME M_D_CPU0_SA_CA<6>
J 0
(-7715 5560);
DISPLAY 0.659574 (-7715 5560);
PAINT MONO (-7715 5560);
DISPLAY INVISIBLE (-7715 5560);
FORCEPROP 1 LASTPIN (-7725 5550) BN 6
J 2
(-7713 5558);
DISPLAY 0.489362 (-7713 5558);
PAINT GREEN (-7713 5558);
FORCEPROP 2 LAST CDS_LIB mstr_standard
J 0
(-7775 5550);
DISPLAY 0.723404 (-7775 5550);
PAINT MONO (-7775 5550);
DISPLAY INVISIBLE (-7775 5550);
FORCEPROP 1 LAST BODY_TYPE PLUMBING
J 2
(-7775 5600);
DISPLAY 0.872340 (-7775 5600);
PAINT GREEN (-7775 5600);
DISPLAY INVISIBLE (-7775 5600);
FORCEPROP 1 LAST HDL_TAP TRUE
J 2
(-8100 5425);
DISPLAY 0.872340 (-8100 5425);
DISPLAY INVISIBLE (-8100 5425);
FORCEPROP 1 LAST PATH I253
J 2
(-7773 5550);
DISPLAY 0.872340 (-7773 5550);
PAINT GREEN (-7773 5550);
DISPLAY INVISIBLE (-7773 5550);
FORCEADD TAP..1
(-6075 4150);
FORCEPROP 3 LASTPIN (-6125 4150) SIG_NAME M_D_CPU0_SA_DQ<3>
J 0
(-6115 4160);
DISPLAY 0.659574 (-6115 4160);
PAINT MONO (-6115 4160);
DISPLAY INVISIBLE (-6115 4160);
FORCEPROP 1 LASTPIN (-6125 4150) BN 3
J 0
(-6137 4158);
DISPLAY 0.489362 (-6137 4158);
PAINT GREEN (-6137 4158);
FORCEPROP 2 LAST CDS_LIB mstr_standard
J 0
(-6075 4150);
DISPLAY 0.723404 (-6075 4150);
PAINT MONO (-6075 4150);
DISPLAY INVISIBLE (-6075 4150);
FORCEPROP 1 LAST BODY_TYPE PLUMBING
J 0
(-6075 4200);
DISPLAY 0.872340 (-6075 4200);
PAINT GREEN (-6075 4200);
DISPLAY INVISIBLE (-6075 4200);
FORCEPROP 1 LAST HDL_TAP TRUE
J 0
(-5750 4025);
DISPLAY 0.872340 (-5750 4025);
DISPLAY INVISIBLE (-5750 4025);
FORCEPROP 1 LAST PATH I254
J 0
(-6077 4150);
DISPLAY 0.872340 (-6077 4150);
PAINT GREEN (-6077 4150);
DISPLAY INVISIBLE (-6077 4150);
FORCEADD TAP..1
(-6075 4200);
FORCEPROP 3 LASTPIN (-6125 4200) SIG_NAME M_D_CPU0_SA_DQ<4>
J 0
(-6115 4210);
DISPLAY 0.659574 (-6115 4210);
PAINT MONO (-6115 4210);
DISPLAY INVISIBLE (-6115 4210);
FORCEPROP 1 LASTPIN (-6125 4200) BN 4
J 0
(-6137 4208);
DISPLAY 0.489362 (-6137 4208);
PAINT GREEN (-6137 4208);
FORCEPROP 2 LAST CDS_LIB mstr_standard
J 0
(-6075 4200);
DISPLAY 0.723404 (-6075 4200);
PAINT MONO (-6075 4200);
DISPLAY INVISIBLE (-6075 4200);
FORCEPROP 1 LAST BODY_TYPE PLUMBING
J 0
(-6075 4250);
DISPLAY 0.872340 (-6075 4250);
PAINT GREEN (-6075 4250);
DISPLAY INVISIBLE (-6075 4250);
FORCEPROP 1 LAST HDL_TAP TRUE
J 0
(-5750 4075);
DISPLAY 0.872340 (-5750 4075);
DISPLAY INVISIBLE (-5750 4075);
FORCEPROP 1 LAST PATH I255
J 0
(-6077 4200);
DISPLAY 0.872340 (-6077 4200);
PAINT GREEN (-6077 4200);
DISPLAY INVISIBLE (-6077 4200);
FORCEADD TAP..1
(-6075 4250);
FORCEPROP 3 LASTPIN (-6125 4250) SIG_NAME M_D_CPU0_SA_DQ<5>
J 0
(-6115 4260);
DISPLAY 0.659574 (-6115 4260);
PAINT MONO (-6115 4260);
DISPLAY INVISIBLE (-6115 4260);
FORCEPROP 1 LASTPIN (-6125 4250) BN 5
J 0
(-6137 4258);
DISPLAY 0.489362 (-6137 4258);
PAINT GREEN (-6137 4258);
FORCEPROP 2 LAST CDS_LIB mstr_standard
J 0
(-6075 4250);
DISPLAY 0.723404 (-6075 4250);
PAINT MONO (-6075 4250);
DISPLAY INVISIBLE (-6075 4250);
FORCEPROP 1 LAST BODY_TYPE PLUMBING
J 0
(-6075 4300);
DISPLAY 0.872340 (-6075 4300);
PAINT GREEN (-6075 4300);
DISPLAY INVISIBLE (-6075 4300);
FORCEPROP 1 LAST HDL_TAP TRUE
J 0
(-5750 4125);
DISPLAY 0.872340 (-5750 4125);
DISPLAY INVISIBLE (-5750 4125);
FORCEPROP 1 LAST PATH I256
J 0
(-6077 4250);
DISPLAY 0.872340 (-6077 4250);
PAINT GREEN (-6077 4250);
DISPLAY INVISIBLE (-6077 4250);
FORCEADD TAP..1
(-6075 4350);
FORCEPROP 3 LASTPIN (-6125 4350) SIG_NAME M_D_CPU0_SA_DQ<7>
J 0
(-6115 4360);
DISPLAY 0.659574 (-6115 4360);
PAINT MONO (-6115 4360);
DISPLAY INVISIBLE (-6115 4360);
FORCEPROP 1 LASTPIN (-6125 4350) BN 7
J 0
(-6137 4358);
DISPLAY 0.489362 (-6137 4358);
PAINT GREEN (-6137 4358);
FORCEPROP 2 LAST CDS_LIB mstr_standard
J 0
(-6075 4350);
DISPLAY 0.723404 (-6075 4350);
PAINT MONO (-6075 4350);
DISPLAY INVISIBLE (-6075 4350);
FORCEPROP 1 LAST BODY_TYPE PLUMBING
J 0
(-6075 4400);
DISPLAY 0.872340 (-6075 4400);
PAINT GREEN (-6075 4400);
DISPLAY INVISIBLE (-6075 4400);
FORCEPROP 1 LAST HDL_TAP TRUE
J 0
(-5750 4225);
DISPLAY 0.872340 (-5750 4225);
DISPLAY INVISIBLE (-5750 4225);
FORCEPROP 1 LAST PATH I257
J 0
(-6077 4350);
DISPLAY 0.872340 (-6077 4350);
PAINT GREEN (-6077 4350);
DISPLAY INVISIBLE (-6077 4350);
FORCEADD TAP..1
(-6075 4300);
FORCEPROP 3 LASTPIN (-6125 4300) SIG_NAME M_D_CPU0_SA_DQ<6>
J 0
(-6115 4310);
DISPLAY 0.659574 (-6115 4310);
PAINT MONO (-6115 4310);
DISPLAY INVISIBLE (-6115 4310);
FORCEPROP 1 LASTPIN (-6125 4300) BN 6
J 0
(-6137 4308);
DISPLAY 0.489362 (-6137 4308);
PAINT GREEN (-6137 4308);
FORCEPROP 2 LAST CDS_LIB mstr_standard
J 0
(-6075 4300);
DISPLAY 0.723404 (-6075 4300);
PAINT MONO (-6075 4300);
DISPLAY INVISIBLE (-6075 4300);
FORCEPROP 1 LAST BODY_TYPE PLUMBING
J 0
(-6075 4350);
DISPLAY 0.872340 (-6075 4350);
PAINT GREEN (-6075 4350);
DISPLAY INVISIBLE (-6075 4350);
FORCEPROP 1 LAST HDL_TAP TRUE
J 0
(-5750 4175);
DISPLAY 0.872340 (-5750 4175);
DISPLAY INVISIBLE (-5750 4175);
FORCEPROP 1 LAST PATH I258
J 0
(-6077 4300);
DISPLAY 0.872340 (-6077 4300);
PAINT GREEN (-6077 4300);
DISPLAY INVISIBLE (-6077 4300);
FORCEADD TAP..1
(-6075 4400);
FORCEPROP 3 LASTPIN (-6125 4400) SIG_NAME M_D_CPU0_SA_DQ<8>
J 0
(-6115 4410);
DISPLAY 0.659574 (-6115 4410);
PAINT MONO (-6115 4410);
DISPLAY INVISIBLE (-6115 4410);
FORCEPROP 1 LASTPIN (-6125 4400) BN 8
J 0
(-6137 4408);
DISPLAY 0.489362 (-6137 4408);
PAINT GREEN (-6137 4408);
FORCEPROP 2 LAST CDS_LIB mstr_standard
J 0
(-6075 4400);
DISPLAY 0.723404 (-6075 4400);
PAINT MONO (-6075 4400);
DISPLAY INVISIBLE (-6075 4400);
FORCEPROP 1 LAST BODY_TYPE PLUMBING
J 0
(-6075 4450);
DISPLAY 0.872340 (-6075 4450);
PAINT GREEN (-6075 4450);
DISPLAY INVISIBLE (-6075 4450);
FORCEPROP 1 LAST HDL_TAP TRUE
J 0
(-5750 4275);
DISPLAY 0.872340 (-5750 4275);
DISPLAY INVISIBLE (-5750 4275);
FORCEPROP 1 LAST PATH I259
J 0
(-6077 4400);
DISPLAY 0.872340 (-6077 4400);
PAINT GREEN (-6077 4400);
DISPLAY INVISIBLE (-6077 4400);
FORCEADD TAP..1
(-6075 4450);
FORCEPROP 3 LASTPIN (-6125 4450) SIG_NAME M_D_CPU0_SA_DQ<9>
J 0
(-6115 4460);
DISPLAY 0.659574 (-6115 4460);
PAINT MONO (-6115 4460);
DISPLAY INVISIBLE (-6115 4460);
FORCEPROP 1 LASTPIN (-6125 4450) BN 9
J 0
(-6137 4458);
DISPLAY 0.489362 (-6137 4458);
PAINT GREEN (-6137 4458);
FORCEPROP 2 LAST CDS_LIB mstr_standard
J 0
(-6075 4450);
DISPLAY 0.723404 (-6075 4450);
PAINT MONO (-6075 4450);
DISPLAY INVISIBLE (-6075 4450);
FORCEPROP 1 LAST BODY_TYPE PLUMBING
J 0
(-6075 4500);
DISPLAY 0.872340 (-6075 4500);
PAINT GREEN (-6075 4500);
DISPLAY INVISIBLE (-6075 4500);
FORCEPROP 1 LAST HDL_TAP TRUE
J 0
(-5750 4325);
DISPLAY 0.872340 (-5750 4325);
DISPLAY INVISIBLE (-5750 4325);
FORCEPROP 1 LAST PATH I260
J 0
(-6077 4450);
DISPLAY 0.872340 (-6077 4450);
PAINT GREEN (-6077 4450);
DISPLAY INVISIBLE (-6077 4450);
FORCEADD TAP..1
(-6075 4500);
FORCEPROP 3 LASTPIN (-6125 4500) SIG_NAME M_D_CPU0_SA_DQ<10>
J 0
(-6115 4510);
DISPLAY 0.659574 (-6115 4510);
PAINT MONO (-6115 4510);
DISPLAY INVISIBLE (-6115 4510);
FORCEPROP 1 LASTPIN (-6125 4500) BN 10
J 0
(-6137 4508);
DISPLAY 0.489362 (-6137 4508);
PAINT GREEN (-6137 4508);
FORCEPROP 2 LAST CDS_LIB mstr_standard
J 0
(-6075 4500);
DISPLAY 0.723404 (-6075 4500);
PAINT MONO (-6075 4500);
DISPLAY INVISIBLE (-6075 4500);
FORCEPROP 1 LAST BODY_TYPE PLUMBING
J 0
(-6075 4550);
DISPLAY 0.872340 (-6075 4550);
PAINT GREEN (-6075 4550);
DISPLAY INVISIBLE (-6075 4550);
FORCEPROP 1 LAST HDL_TAP TRUE
J 0
(-5750 4375);
DISPLAY 0.872340 (-5750 4375);
DISPLAY INVISIBLE (-5750 4375);
FORCEPROP 1 LAST PATH I261
J 0
(-6077 4500);
DISPLAY 0.872340 (-6077 4500);
PAINT GREEN (-6077 4500);
DISPLAY INVISIBLE (-6077 4500);
FORCEADD TAP..1
(-6075 4550);
FORCEPROP 3 LASTPIN (-6125 4550) SIG_NAME M_D_CPU0_SA_DQ<11>
J 0
(-6115 4560);
DISPLAY 0.659574 (-6115 4560);
PAINT MONO (-6115 4560);
DISPLAY INVISIBLE (-6115 4560);
FORCEPROP 1 LASTPIN (-6125 4550) BN 11
J 0
(-6137 4558);
DISPLAY 0.489362 (-6137 4558);
PAINT GREEN (-6137 4558);
FORCEPROP 2 LAST CDS_LIB mstr_standard
J 0
(-6075 4550);
DISPLAY 0.723404 (-6075 4550);
PAINT MONO (-6075 4550);
DISPLAY INVISIBLE (-6075 4550);
FORCEPROP 1 LAST BODY_TYPE PLUMBING
J 0
(-6075 4600);
DISPLAY 0.872340 (-6075 4600);
PAINT GREEN (-6075 4600);
DISPLAY INVISIBLE (-6075 4600);
FORCEPROP 1 LAST HDL_TAP TRUE
J 0
(-5750 4425);
DISPLAY 0.872340 (-5750 4425);
DISPLAY INVISIBLE (-5750 4425);
FORCEPROP 1 LAST PATH I262
J 0
(-6077 4550);
DISPLAY 0.872340 (-6077 4550);
PAINT GREEN (-6077 4550);
DISPLAY INVISIBLE (-6077 4550);
FORCEADD TAP..1
(-6075 4600);
FORCEPROP 3 LASTPIN (-6125 4600) SIG_NAME M_D_CPU0_SA_DQ<12>
J 0
(-6115 4610);
DISPLAY 0.659574 (-6115 4610);
PAINT MONO (-6115 4610);
DISPLAY INVISIBLE (-6115 4610);
FORCEPROP 1 LASTPIN (-6125 4600) BN 12
J 0
(-6137 4608);
DISPLAY 0.489362 (-6137 4608);
PAINT GREEN (-6137 4608);
FORCEPROP 2 LAST CDS_LIB mstr_standard
J 0
(-6075 4600);
DISPLAY 0.723404 (-6075 4600);
PAINT MONO (-6075 4600);
DISPLAY INVISIBLE (-6075 4600);
FORCEPROP 1 LAST BODY_TYPE PLUMBING
J 0
(-6075 4650);
DISPLAY 0.872340 (-6075 4650);
PAINT GREEN (-6075 4650);
DISPLAY INVISIBLE (-6075 4650);
FORCEPROP 1 LAST HDL_TAP TRUE
J 0
(-5750 4475);
DISPLAY 0.872340 (-5750 4475);
DISPLAY INVISIBLE (-5750 4475);
FORCEPROP 1 LAST PATH I263
J 0
(-6077 4600);
DISPLAY 0.872340 (-6077 4600);
PAINT GREEN (-6077 4600);
DISPLAY INVISIBLE (-6077 4600);
FORCEADD TAP..1
(-6075 4650);
FORCEPROP 3 LASTPIN (-6125 4650) SIG_NAME M_D_CPU0_SA_DQ<13>
J 0
(-6115 4660);
DISPLAY 0.659574 (-6115 4660);
PAINT MONO (-6115 4660);
DISPLAY INVISIBLE (-6115 4660);
FORCEPROP 1 LASTPIN (-6125 4650) BN 13
J 0
(-6137 4658);
DISPLAY 0.489362 (-6137 4658);
PAINT GREEN (-6137 4658);
FORCEPROP 2 LAST CDS_LIB mstr_standard
J 0
(-6075 4650);
DISPLAY 0.723404 (-6075 4650);
PAINT MONO (-6075 4650);
DISPLAY INVISIBLE (-6075 4650);
FORCEPROP 1 LAST BODY_TYPE PLUMBING
J 0
(-6075 4700);
DISPLAY 0.872340 (-6075 4700);
PAINT GREEN (-6075 4700);
DISPLAY INVISIBLE (-6075 4700);
FORCEPROP 1 LAST HDL_TAP TRUE
J 0
(-5750 4525);
DISPLAY 0.872340 (-5750 4525);
DISPLAY INVISIBLE (-5750 4525);
FORCEPROP 1 LAST PATH I264
J 0
(-6077 4650);
DISPLAY 0.872340 (-6077 4650);
PAINT GREEN (-6077 4650);
DISPLAY INVISIBLE (-6077 4650);
FORCEADD TAP..1
(-6075 4700);
FORCEPROP 3 LASTPIN (-6125 4700) SIG_NAME M_D_CPU0_SA_DQ<14>
J 0
(-6115 4710);
DISPLAY 0.659574 (-6115 4710);
PAINT MONO (-6115 4710);
DISPLAY INVISIBLE (-6115 4710);
FORCEPROP 1 LASTPIN (-6125 4700) BN 14
J 0
(-6137 4708);
DISPLAY 0.489362 (-6137 4708);
PAINT GREEN (-6137 4708);
FORCEPROP 2 LAST CDS_LIB mstr_standard
J 0
(-6075 4700);
DISPLAY 0.723404 (-6075 4700);
PAINT MONO (-6075 4700);
DISPLAY INVISIBLE (-6075 4700);
FORCEPROP 1 LAST BODY_TYPE PLUMBING
J 0
(-6075 4750);
DISPLAY 0.872340 (-6075 4750);
PAINT GREEN (-6075 4750);
DISPLAY INVISIBLE (-6075 4750);
FORCEPROP 1 LAST HDL_TAP TRUE
J 0
(-5750 4575);
DISPLAY 0.872340 (-5750 4575);
DISPLAY INVISIBLE (-5750 4575);
FORCEPROP 1 LAST PATH I265
J 0
(-6077 4700);
DISPLAY 0.872340 (-6077 4700);
PAINT GREEN (-6077 4700);
DISPLAY INVISIBLE (-6077 4700);
FORCEADD TAP..1
(-6075 4750);
FORCEPROP 3 LASTPIN (-6125 4750) SIG_NAME M_D_CPU0_SA_DQ<15>
J 0
(-6115 4760);
DISPLAY 0.659574 (-6115 4760);
PAINT MONO (-6115 4760);
DISPLAY INVISIBLE (-6115 4760);
FORCEPROP 1 LASTPIN (-6125 4750) BN 15
J 0
(-6137 4758);
DISPLAY 0.489362 (-6137 4758);
PAINT GREEN (-6137 4758);
FORCEPROP 2 LAST CDS_LIB mstr_standard
J 0
(-6075 4750);
DISPLAY 0.723404 (-6075 4750);
PAINT MONO (-6075 4750);
DISPLAY INVISIBLE (-6075 4750);
FORCEPROP 1 LAST BODY_TYPE PLUMBING
J 0
(-6075 4800);
DISPLAY 0.872340 (-6075 4800);
PAINT GREEN (-6075 4800);
DISPLAY INVISIBLE (-6075 4800);
FORCEPROP 1 LAST HDL_TAP TRUE
J 0
(-5750 4625);
DISPLAY 0.872340 (-5750 4625);
DISPLAY INVISIBLE (-5750 4625);
FORCEPROP 1 LAST PATH I266
J 0
(-6077 4750);
DISPLAY 0.872340 (-6077 4750);
PAINT GREEN (-6077 4750);
DISPLAY INVISIBLE (-6077 4750);
FORCEADD TAP..1
(-6075 4850);
FORCEPROP 3 LASTPIN (-6125 4850) SIG_NAME M_D_CPU0_SA_DQ<17>
J 0
(-6115 4860);
DISPLAY 0.659574 (-6115 4860);
PAINT MONO (-6115 4860);
DISPLAY INVISIBLE (-6115 4860);
FORCEPROP 1 LASTPIN (-6125 4850) BN 17
J 0
(-6137 4858);
DISPLAY 0.489362 (-6137 4858);
PAINT GREEN (-6137 4858);
FORCEPROP 2 LAST CDS_LIB mstr_standard
J 0
(-6075 4850);
DISPLAY 0.723404 (-6075 4850);
PAINT MONO (-6075 4850);
DISPLAY INVISIBLE (-6075 4850);
FORCEPROP 1 LAST BODY_TYPE PLUMBING
J 0
(-6075 4900);
DISPLAY 0.872340 (-6075 4900);
PAINT GREEN (-6075 4900);
DISPLAY INVISIBLE (-6075 4900);
FORCEPROP 1 LAST HDL_TAP TRUE
J 0
(-5750 4725);
DISPLAY 0.872340 (-5750 4725);
DISPLAY INVISIBLE (-5750 4725);
FORCEPROP 1 LAST PATH I267
J 0
(-6077 4850);
DISPLAY 0.872340 (-6077 4850);
PAINT GREEN (-6077 4850);
DISPLAY INVISIBLE (-6077 4850);
FORCEADD TAP..1
(-6075 4900);
FORCEPROP 3 LASTPIN (-6125 4900) SIG_NAME M_D_CPU0_SA_DQ<18>
J 0
(-6115 4910);
DISPLAY 0.659574 (-6115 4910);
PAINT MONO (-6115 4910);
DISPLAY INVISIBLE (-6115 4910);
FORCEPROP 1 LASTPIN (-6125 4900) BN 18
J 0
(-6137 4908);
DISPLAY 0.489362 (-6137 4908);
PAINT GREEN (-6137 4908);
FORCEPROP 2 LAST CDS_LIB mstr_standard
J 0
(-6075 4900);
DISPLAY 0.723404 (-6075 4900);
PAINT MONO (-6075 4900);
DISPLAY INVISIBLE (-6075 4900);
FORCEPROP 1 LAST BODY_TYPE PLUMBING
J 0
(-6075 4950);
DISPLAY 0.872340 (-6075 4950);
PAINT GREEN (-6075 4950);
DISPLAY INVISIBLE (-6075 4950);
FORCEPROP 1 LAST HDL_TAP TRUE
J 0
(-5750 4775);
DISPLAY 0.872340 (-5750 4775);
DISPLAY INVISIBLE (-5750 4775);
FORCEPROP 1 LAST PATH I268
J 0
(-6077 4900);
DISPLAY 0.872340 (-6077 4900);
PAINT GREEN (-6077 4900);
DISPLAY INVISIBLE (-6077 4900);
FORCEADD TAP..1
(-6075 4800);
FORCEPROP 3 LASTPIN (-6125 4800) SIG_NAME M_D_CPU0_SA_DQ<16>
J 0
(-6115 4810);
DISPLAY 0.659574 (-6115 4810);
PAINT MONO (-6115 4810);
DISPLAY INVISIBLE (-6115 4810);
FORCEPROP 1 LASTPIN (-6125 4800) BN 16
J 0
(-6137 4808);
DISPLAY 0.489362 (-6137 4808);
PAINT GREEN (-6137 4808);
FORCEPROP 2 LAST CDS_LIB mstr_standard
J 0
(-6075 4800);
DISPLAY 0.723404 (-6075 4800);
PAINT MONO (-6075 4800);
DISPLAY INVISIBLE (-6075 4800);
FORCEPROP 1 LAST BODY_TYPE PLUMBING
J 0
(-6075 4850);
DISPLAY 0.872340 (-6075 4850);
PAINT GREEN (-6075 4850);
DISPLAY INVISIBLE (-6075 4850);
FORCEPROP 1 LAST HDL_TAP TRUE
J 0
(-5750 4675);
DISPLAY 0.872340 (-5750 4675);
DISPLAY INVISIBLE (-5750 4675);
FORCEPROP 1 LAST PATH I269
J 0
(-6077 4800);
DISPLAY 0.872340 (-6077 4800);
PAINT GREEN (-6077 4800);
DISPLAY INVISIBLE (-6077 4800);
FORCEADD TAP..1
(-6075 4950);
FORCEPROP 3 LASTPIN (-6125 4950) SIG_NAME M_D_CPU0_SA_DQ<19>
J 0
(-6115 4960);
DISPLAY 0.659574 (-6115 4960);
PAINT MONO (-6115 4960);
DISPLAY INVISIBLE (-6115 4960);
FORCEPROP 1 LASTPIN (-6125 4950) BN 19
J 0
(-6137 4958);
DISPLAY 0.489362 (-6137 4958);
PAINT GREEN (-6137 4958);
FORCEPROP 2 LAST CDS_LIB mstr_standard
J 0
(-6075 4950);
DISPLAY 0.723404 (-6075 4950);
PAINT MONO (-6075 4950);
DISPLAY INVISIBLE (-6075 4950);
FORCEPROP 1 LAST BODY_TYPE PLUMBING
J 0
(-6075 5000);
DISPLAY 0.872340 (-6075 5000);
PAINT GREEN (-6075 5000);
DISPLAY INVISIBLE (-6075 5000);
FORCEPROP 1 LAST HDL_TAP TRUE
J 0
(-5750 4825);
DISPLAY 0.872340 (-5750 4825);
DISPLAY INVISIBLE (-5750 4825);
FORCEPROP 1 LAST PATH I270
J 0
(-6077 4950);
DISPLAY 0.872340 (-6077 4950);
PAINT GREEN (-6077 4950);
DISPLAY INVISIBLE (-6077 4950);
FORCEADD TAP..1
(-6075 5000);
FORCEPROP 3 LASTPIN (-6125 5000) SIG_NAME M_D_CPU0_SA_DQ<20>
J 0
(-6115 5010);
DISPLAY 0.659574 (-6115 5010);
PAINT MONO (-6115 5010);
DISPLAY INVISIBLE (-6115 5010);
FORCEPROP 1 LASTPIN (-6125 5000) BN 20
J 0
(-6137 5008);
DISPLAY 0.489362 (-6137 5008);
PAINT GREEN (-6137 5008);
FORCEPROP 2 LAST CDS_LIB mstr_standard
J 0
(-6075 5000);
DISPLAY 0.723404 (-6075 5000);
PAINT MONO (-6075 5000);
DISPLAY INVISIBLE (-6075 5000);
FORCEPROP 1 LAST BODY_TYPE PLUMBING
J 0
(-6075 5050);
DISPLAY 0.872340 (-6075 5050);
PAINT GREEN (-6075 5050);
DISPLAY INVISIBLE (-6075 5050);
FORCEPROP 1 LAST HDL_TAP TRUE
J 0
(-5750 4875);
DISPLAY 0.872340 (-5750 4875);
DISPLAY INVISIBLE (-5750 4875);
FORCEPROP 1 LAST PATH I271
J 0
(-6077 5000);
DISPLAY 0.872340 (-6077 5000);
PAINT GREEN (-6077 5000);
DISPLAY INVISIBLE (-6077 5000);
FORCEADD TAP..1
(-6075 5100);
FORCEPROP 3 LASTPIN (-6125 5100) SIG_NAME M_D_CPU0_SA_DQ<22>
J 0
(-6115 5110);
DISPLAY 0.659574 (-6115 5110);
PAINT MONO (-6115 5110);
DISPLAY INVISIBLE (-6115 5110);
FORCEPROP 1 LASTPIN (-6125 5100) BN 22
J 0
(-6137 5108);
DISPLAY 0.489362 (-6137 5108);
PAINT GREEN (-6137 5108);
FORCEPROP 2 LAST CDS_LIB mstr_standard
J 0
(-6075 5100);
DISPLAY 0.723404 (-6075 5100);
PAINT MONO (-6075 5100);
DISPLAY INVISIBLE (-6075 5100);
FORCEPROP 1 LAST BODY_TYPE PLUMBING
J 0
(-6075 5150);
DISPLAY 0.872340 (-6075 5150);
PAINT GREEN (-6075 5150);
DISPLAY INVISIBLE (-6075 5150);
FORCEPROP 1 LAST HDL_TAP TRUE
J 0
(-5750 4975);
DISPLAY 0.872340 (-5750 4975);
DISPLAY INVISIBLE (-5750 4975);
FORCEPROP 1 LAST PATH I272
J 0
(-6077 5100);
DISPLAY 0.872340 (-6077 5100);
PAINT GREEN (-6077 5100);
DISPLAY INVISIBLE (-6077 5100);
FORCEADD TAP..1
(-6075 5050);
FORCEPROP 3 LASTPIN (-6125 5050) SIG_NAME M_D_CPU0_SA_DQ<21>
J 0
(-6115 5060);
DISPLAY 0.659574 (-6115 5060);
PAINT MONO (-6115 5060);
DISPLAY INVISIBLE (-6115 5060);
FORCEPROP 1 LASTPIN (-6125 5050) BN 21
J 0
(-6137 5058);
DISPLAY 0.489362 (-6137 5058);
PAINT GREEN (-6137 5058);
FORCEPROP 2 LAST CDS_LIB mstr_standard
J 0
(-6075 5050);
DISPLAY 0.723404 (-6075 5050);
PAINT MONO (-6075 5050);
DISPLAY INVISIBLE (-6075 5050);
FORCEPROP 1 LAST BODY_TYPE PLUMBING
J 0
(-6075 5100);
DISPLAY 0.872340 (-6075 5100);
PAINT GREEN (-6075 5100);
DISPLAY INVISIBLE (-6075 5100);
FORCEPROP 1 LAST HDL_TAP TRUE
J 0
(-5750 4925);
DISPLAY 0.872340 (-5750 4925);
DISPLAY INVISIBLE (-5750 4925);
FORCEPROP 1 LAST PATH I273
J 0
(-6077 5050);
DISPLAY 0.872340 (-6077 5050);
PAINT GREEN (-6077 5050);
DISPLAY INVISIBLE (-6077 5050);
FORCEADD TAP..1
(-6075 5150);
FORCEPROP 3 LASTPIN (-6125 5150) SIG_NAME M_D_CPU0_SA_DQ<23>
J 0
(-6115 5160);
DISPLAY 0.659574 (-6115 5160);
PAINT MONO (-6115 5160);
DISPLAY INVISIBLE (-6115 5160);
FORCEPROP 1 LASTPIN (-6125 5150) BN 23
J 0
(-6137 5158);
DISPLAY 0.489362 (-6137 5158);
PAINT GREEN (-6137 5158);
FORCEPROP 2 LAST CDS_LIB mstr_standard
J 0
(-6075 5150);
DISPLAY 0.723404 (-6075 5150);
PAINT MONO (-6075 5150);
DISPLAY INVISIBLE (-6075 5150);
FORCEPROP 1 LAST BODY_TYPE PLUMBING
J 0
(-6075 5200);
DISPLAY 0.872340 (-6075 5200);
PAINT GREEN (-6075 5200);
DISPLAY INVISIBLE (-6075 5200);
FORCEPROP 1 LAST HDL_TAP TRUE
J 0
(-5750 5025);
DISPLAY 0.872340 (-5750 5025);
DISPLAY INVISIBLE (-5750 5025);
FORCEPROP 1 LAST PATH I274
J 0
(-6077 5150);
DISPLAY 0.872340 (-6077 5150);
PAINT GREEN (-6077 5150);
DISPLAY INVISIBLE (-6077 5150);
FORCEADD TAP..1
(-6075 5200);
FORCEPROP 3 LASTPIN (-6125 5200) SIG_NAME M_D_CPU0_SA_DQ<24>
J 0
(-6115 5210);
DISPLAY 0.659574 (-6115 5210);
PAINT MONO (-6115 5210);
DISPLAY INVISIBLE (-6115 5210);
FORCEPROP 1 LASTPIN (-6125 5200) BN 24
J 0
(-6137 5208);
DISPLAY 0.489362 (-6137 5208);
PAINT GREEN (-6137 5208);
FORCEPROP 2 LAST CDS_LIB mstr_standard
J 0
(-6075 5200);
DISPLAY 0.723404 (-6075 5200);
PAINT MONO (-6075 5200);
DISPLAY INVISIBLE (-6075 5200);
FORCEPROP 1 LAST BODY_TYPE PLUMBING
J 0
(-6075 5250);
DISPLAY 0.872340 (-6075 5250);
PAINT GREEN (-6075 5250);
DISPLAY INVISIBLE (-6075 5250);
FORCEPROP 1 LAST HDL_TAP TRUE
J 0
(-5750 5075);
DISPLAY 0.872340 (-5750 5075);
DISPLAY INVISIBLE (-5750 5075);
FORCEPROP 1 LAST PATH I275
J 0
(-6077 5200);
DISPLAY 0.872340 (-6077 5200);
PAINT GREEN (-6077 5200);
DISPLAY INVISIBLE (-6077 5200);
FORCEADD TAP..1
(-6075 5250);
FORCEPROP 3 LASTPIN (-6125 5250) SIG_NAME M_D_CPU0_SA_DQ<25>
J 0
(-6115 5260);
DISPLAY 0.659574 (-6115 5260);
PAINT MONO (-6115 5260);
DISPLAY INVISIBLE (-6115 5260);
FORCEPROP 1 LASTPIN (-6125 5250) BN 25
J 0
(-6137 5258);
DISPLAY 0.489362 (-6137 5258);
PAINT GREEN (-6137 5258);
FORCEPROP 2 LAST CDS_LIB mstr_standard
J 0
(-6075 5250);
DISPLAY 0.723404 (-6075 5250);
PAINT MONO (-6075 5250);
DISPLAY INVISIBLE (-6075 5250);
FORCEPROP 1 LAST BODY_TYPE PLUMBING
J 0
(-6075 5300);
DISPLAY 0.872340 (-6075 5300);
PAINT GREEN (-6075 5300);
DISPLAY INVISIBLE (-6075 5300);
FORCEPROP 1 LAST HDL_TAP TRUE
J 0
(-5750 5125);
DISPLAY 0.872340 (-5750 5125);
DISPLAY INVISIBLE (-5750 5125);
FORCEPROP 1 LAST PATH I276
J 0
(-6077 5250);
DISPLAY 0.872340 (-6077 5250);
PAINT GREEN (-6077 5250);
DISPLAY INVISIBLE (-6077 5250);
FORCEADD TAP..1
(-6075 5300);
FORCEPROP 3 LASTPIN (-6125 5300) SIG_NAME M_D_CPU0_SA_DQ<26>
J 0
(-6115 5310);
DISPLAY 0.659574 (-6115 5310);
PAINT MONO (-6115 5310);
DISPLAY INVISIBLE (-6115 5310);
FORCEPROP 1 LASTPIN (-6125 5300) BN 26
J 0
(-6137 5308);
DISPLAY 0.489362 (-6137 5308);
PAINT GREEN (-6137 5308);
FORCEPROP 2 LAST CDS_LIB mstr_standard
J 0
(-6075 5300);
DISPLAY 0.723404 (-6075 5300);
PAINT MONO (-6075 5300);
DISPLAY INVISIBLE (-6075 5300);
FORCEPROP 1 LAST BODY_TYPE PLUMBING
J 0
(-6075 5350);
DISPLAY 0.872340 (-6075 5350);
PAINT GREEN (-6075 5350);
DISPLAY INVISIBLE (-6075 5350);
FORCEPROP 1 LAST HDL_TAP TRUE
J 0
(-5750 5175);
DISPLAY 0.872340 (-5750 5175);
DISPLAY INVISIBLE (-5750 5175);
FORCEPROP 1 LAST PATH I277
J 0
(-6077 5300);
DISPLAY 0.872340 (-6077 5300);
PAINT GREEN (-6077 5300);
DISPLAY INVISIBLE (-6077 5300);
FORCEADD TAP..1
(-6075 5350);
FORCEPROP 3 LASTPIN (-6125 5350) SIG_NAME M_D_CPU0_SA_DQ<27>
J 0
(-6115 5360);
DISPLAY 0.659574 (-6115 5360);
PAINT MONO (-6115 5360);
DISPLAY INVISIBLE (-6115 5360);
FORCEPROP 1 LASTPIN (-6125 5350) BN 27
J 0
(-6137 5358);
DISPLAY 0.489362 (-6137 5358);
PAINT GREEN (-6137 5358);
FORCEPROP 2 LAST CDS_LIB mstr_standard
J 0
(-6075 5350);
DISPLAY 0.723404 (-6075 5350);
PAINT MONO (-6075 5350);
DISPLAY INVISIBLE (-6075 5350);
FORCEPROP 1 LAST BODY_TYPE PLUMBING
J 0
(-6075 5400);
DISPLAY 0.872340 (-6075 5400);
PAINT GREEN (-6075 5400);
DISPLAY INVISIBLE (-6075 5400);
FORCEPROP 1 LAST HDL_TAP TRUE
J 0
(-5750 5225);
DISPLAY 0.872340 (-5750 5225);
DISPLAY INVISIBLE (-5750 5225);
FORCEPROP 1 LAST PATH I278
J 0
(-6077 5350);
DISPLAY 0.872340 (-6077 5350);
PAINT GREEN (-6077 5350);
DISPLAY INVISIBLE (-6077 5350);
FORCEADD TAP..1
(-6075 5400);
FORCEPROP 3 LASTPIN (-6125 5400) SIG_NAME M_D_CPU0_SA_DQ<28>
J 0
(-6115 5410);
DISPLAY 0.659574 (-6115 5410);
PAINT MONO (-6115 5410);
DISPLAY INVISIBLE (-6115 5410);
FORCEPROP 1 LASTPIN (-6125 5400) BN 28
J 0
(-6137 5408);
DISPLAY 0.489362 (-6137 5408);
PAINT GREEN (-6137 5408);
FORCEPROP 2 LAST CDS_LIB mstr_standard
J 0
(-6075 5400);
DISPLAY 0.723404 (-6075 5400);
PAINT MONO (-6075 5400);
DISPLAY INVISIBLE (-6075 5400);
FORCEPROP 1 LAST BODY_TYPE PLUMBING
J 0
(-6075 5450);
DISPLAY 0.872340 (-6075 5450);
PAINT GREEN (-6075 5450);
DISPLAY INVISIBLE (-6075 5450);
FORCEPROP 1 LAST HDL_TAP TRUE
J 0
(-5750 5275);
DISPLAY 0.872340 (-5750 5275);
DISPLAY INVISIBLE (-5750 5275);
FORCEPROP 1 LAST PATH I279
J 0
(-6077 5400);
DISPLAY 0.872340 (-6077 5400);
PAINT GREEN (-6077 5400);
DISPLAY INVISIBLE (-6077 5400);
FORCEADD TAP..1
(-6075 5450);
FORCEPROP 3 LASTPIN (-6125 5450) SIG_NAME M_D_CPU0_SA_DQ<29>
J 0
(-6115 5460);
DISPLAY 0.659574 (-6115 5460);
PAINT MONO (-6115 5460);
DISPLAY INVISIBLE (-6115 5460);
FORCEPROP 1 LASTPIN (-6125 5450) BN 29
J 0
(-6137 5458);
DISPLAY 0.489362 (-6137 5458);
PAINT GREEN (-6137 5458);
FORCEPROP 2 LAST CDS_LIB mstr_standard
J 0
(-6075 5450);
DISPLAY 0.723404 (-6075 5450);
PAINT MONO (-6075 5450);
DISPLAY INVISIBLE (-6075 5450);
FORCEPROP 1 LAST BODY_TYPE PLUMBING
J 0
(-6075 5500);
DISPLAY 0.872340 (-6075 5500);
PAINT GREEN (-6075 5500);
DISPLAY INVISIBLE (-6075 5500);
FORCEPROP 1 LAST HDL_TAP TRUE
J 0
(-5750 5325);
DISPLAY 0.872340 (-5750 5325);
DISPLAY INVISIBLE (-5750 5325);
FORCEPROP 1 LAST PATH I280
J 0
(-6077 5450);
DISPLAY 0.872340 (-6077 5450);
PAINT GREEN (-6077 5450);
DISPLAY INVISIBLE (-6077 5450);
FORCEADD TAP..1
(-6075 5500);
FORCEPROP 3 LASTPIN (-6125 5500) SIG_NAME M_D_CPU0_SA_DQ<30>
J 0
(-6115 5510);
DISPLAY 0.659574 (-6115 5510);
PAINT MONO (-6115 5510);
DISPLAY INVISIBLE (-6115 5510);
FORCEPROP 1 LASTPIN (-6125 5500) BN 30
J 0
(-6137 5508);
DISPLAY 0.489362 (-6137 5508);
PAINT GREEN (-6137 5508);
FORCEPROP 2 LAST CDS_LIB mstr_standard
J 0
(-6075 5500);
DISPLAY 0.723404 (-6075 5500);
PAINT MONO (-6075 5500);
DISPLAY INVISIBLE (-6075 5500);
FORCEPROP 1 LAST BODY_TYPE PLUMBING
J 0
(-6075 5550);
DISPLAY 0.872340 (-6075 5550);
PAINT GREEN (-6075 5550);
DISPLAY INVISIBLE (-6075 5550);
FORCEPROP 1 LAST HDL_TAP TRUE
J 0
(-5750 5375);
DISPLAY 0.872340 (-5750 5375);
DISPLAY INVISIBLE (-5750 5375);
FORCEPROP 1 LAST PATH I281
J 0
(-6077 5500);
DISPLAY 0.872340 (-6077 5500);
PAINT GREEN (-6077 5500);
DISPLAY INVISIBLE (-6077 5500);
FORCEADD TAP..1
(-6075 5550);
FORCEPROP 3 LASTPIN (-6125 5550) SIG_NAME M_D_CPU0_SA_DQ<31>
J 0
(-6115 5560);
DISPLAY 0.659574 (-6115 5560);
PAINT MONO (-6115 5560);
DISPLAY INVISIBLE (-6115 5560);
FORCEPROP 1 LASTPIN (-6125 5550) BN 31
J 0
(-6137 5558);
DISPLAY 0.489362 (-6137 5558);
PAINT GREEN (-6137 5558);
FORCEPROP 2 LAST CDS_LIB mstr_standard
J 0
(-6075 5550);
DISPLAY 0.723404 (-6075 5550);
PAINT MONO (-6075 5550);
DISPLAY INVISIBLE (-6075 5550);
FORCEPROP 1 LAST BODY_TYPE PLUMBING
J 0
(-6075 5600);
DISPLAY 0.872340 (-6075 5600);
PAINT GREEN (-6075 5600);
DISPLAY INVISIBLE (-6075 5600);
FORCEPROP 1 LAST HDL_TAP TRUE
J 0
(-5750 5425);
DISPLAY 0.872340 (-5750 5425);
DISPLAY INVISIBLE (-5750 5425);
FORCEPROP 1 LAST PATH I282
J 0
(-6077 5550);
DISPLAY 0.872340 (-6077 5550);
PAINT GREEN (-6077 5550);
DISPLAY INVISIBLE (-6077 5550);
FORCEADD OFFPAGE..3
(-5525 3950);
FORCEPROP 2 LAST $XR0 13 
J 0
(-5221 3950);
DISPLAY 0.638298 (-5221 3950);
PAINT MONO (-5221 3950);
FORCEPROP 2 LAST CDS_LIB mstr_standard
J 0
(-5525 3950);
DISPLAY 0.723404 (-5525 3950);
PAINT MONO (-5525 3950);
DISPLAY INVISIBLE (-5525 3950);
FORCEPROP 1 LAST OFFPAGE TRUE
J 0
(-5200 3825);
DISPLAY 0.872340 (-5200 3825);
PAINT GREEN (-5200 3825);
DISPLAY INVISIBLE (-5200 3825);
FORCEPROP 1 LAST COMMENT_BODY TRUE
J 0
(-5575 3850);
DISPLAY 0.872340 (-5575 3850);
PAINT GREEN (-5575 3850);
DISPLAY INVISIBLE (-5575 3850);
FORCEPROP 2 LAST PATH I283
J 0
(-5200 4000);
DISPLAY 0.808511 (-5200 4000);
DISPLAY INVISIBLE (-5200 4000);
FORCEADD OFFPAGE..3
(-5525 5600);
FORCEPROP 2 LAST $XR0 13 
J 0
(-5311 5600);
DISPLAY 0.638298 (-5311 5600);
PAINT MONO (-5311 5600);
FORCEPROP 2 LAST CDS_LIB mstr_standard
J 0
(-5525 5600);
DISPLAY 0.723404 (-5525 5600);
PAINT MONO (-5525 5600);
DISPLAY INVISIBLE (-5525 5600);
FORCEPROP 1 LAST OFFPAGE TRUE
J 0
(-5200 5475);
DISPLAY 0.872340 (-5200 5475);
PAINT GREEN (-5200 5475);
DISPLAY INVISIBLE (-5200 5475);
FORCEPROP 1 LAST COMMENT_BODY TRUE
J 0
(-5575 5500);
DISPLAY 0.872340 (-5575 5500);
PAINT GREEN (-5575 5500);
DISPLAY INVISIBLE (-5575 5500);
FORCEPROP 2 LAST PATH I290
J 0
(-5300 5650);
DISPLAY 0.808511 (-5300 5650);
DISPLAY INVISIBLE (-5300 5650);
FORCEADD GND..1
(-6450 1175);
FORCEPROP 3 LASTPIN (-6450 1225) SIG_NAME GND\g
J 0
(-6440 1235);
DISPLAY 0.659574 (-6440 1235);
PAINT MONO (-6440 1235);
DISPLAY INVISIBLE (-6440 1235);
FORCEPROP 1 LAST SIZE 1B
J 0
(-6375 1125);
DISPLAY 0.851064 (-6375 1125);
PAINT GREEN (-6375 1125);
DISPLAY INVISIBLE (-6375 1125);
FORCEPROP 2 LAST CDS_LIB mstr_symbols
J 0
(-6450 1175);
DISPLAY 0.808511 (-6450 1175);
DISPLAY INVISIBLE (-6450 1175);
FORCEPROP 2 LAST BOM_COST MEM
J 0
(-6550 1250);
DISPLAY 0.808511 (-6550 1250);
DISPLAY INVISIBLE (-6550 1250);
FORCEPROP 1 LAST VOLTAGE 0.0
J 0
(-6495 1132);
DISPLAY 0.723404 (-6495 1132);
PAINT SKYBLUE (-6495 1132);
DISPLAY INVISIBLE (-6495 1132);
FORCEPROP 1 LAST BODY_TYPE PLUMBING
J 0
(-6495 1132);
DISPLAY 0.340426 (-6495 1132);
PAINT GREEN (-6495 1132);
DISPLAY INVISIBLE (-6495 1132);
FORCEPROP 1 LAST HDL_POWER GND
J 0
(-6450 1325);
DISPLAY 0.851064 (-6450 1325);
PAINT GREEN (-6450 1325);
DISPLAY INVISIBLE (-6450 1325);
FORCEPROP 1 LAST PATH I332
J 0
(-6375 1175);
DISPLAY 0.872340 (-6375 1175);
PAINT GREEN (-6375 1175);
DISPLAY INVISIBLE (-6375 1175);
FORCEADD OFFPAGE..5
(-7225 1600);
FORCEPROP 2 LAST $XR0 89 
J 0
(-7449 1600);
DISPLAY 0.638298 (-7449 1600);
PAINT MONO (-7449 1600);
FORCEPROP 2 LAST CDS_LIB mstr_standard
J 0
(-7225 1600);
DISPLAY 0.808511 (-7225 1600);
DISPLAY INVISIBLE (-7225 1600);
FORCEPROP 2 LAST BOM_COST MEM
J 0
(-7300 1675);
DISPLAY 0.808511 (-7300 1675);
DISPLAY INVISIBLE (-7300 1675);
FORCEPROP 1 LAST OFFPAGE TRUE
J 0
(-6900 1475);
DISPLAY 0.872340 (-6900 1475);
PAINT GREEN (-6900 1475);
DISPLAY INVISIBLE (-6900 1475);
FORCEPROP 1 LAST COMMENT_BODY TRUE
J 0
(-7125 1525);
DISPLAY 0.872340 (-7125 1525);
PAINT GREEN (-7125 1525);
DISPLAY INVISIBLE (-7125 1525);
FORCEPROP 2 LAST PATH I333
J 0
(-7175 1675);
DISPLAY 0.808511 (-7175 1675);
DISPLAY INVISIBLE (-7175 1675);
FORCEADD OFFPAGE..1
(-8375 3050);
FORCEPROP 2 LAST $XR0 89 
J 0
(-8626 3050);
DISPLAY 0.638298 (-8626 3050);
PAINT MONO (-8626 3050);
FORCEPROP 2 LAST CDS_LIB mstr_standard
J 0
(-8375 3050);
DISPLAY 0.808511 (-8375 3050);
DISPLAY INVISIBLE (-8375 3050);
FORCEPROP 1 LAST OFFPAGE TRUE
J 0
(-8050 2925);
DISPLAY 0.872340 (-8050 2925);
PAINT GREEN (-8050 2925);
DISPLAY INVISIBLE (-8050 2925);
FORCEPROP 1 LAST COMMENT_BODY TRUE
J 0
(-8250 2950);
DISPLAY 0.872340 (-8250 2950);
PAINT GREEN (-8250 2950);
DISPLAY INVISIBLE (-8250 2950);
FORCEPROP 2 LAST PATH I334
J 0
(-8325 3125);
DISPLAY 0.808511 (-8325 3125);
DISPLAY INVISIBLE (-8325 3125);
FORCEADD Q_RES..2
(-6450 1425);
FORCEPROP 1 LAST LOCATION R763
J 0
(-6405 1550);
DISPLAY 0.489362 (-6405 1550);
PAINT SKYBLUE (-6405 1550);
FORCEPROP 0 LAST $SEC 1
J 0
(-6400 1600);
DISPLAY 0.680851 (-6400 1600);
PAINT MONO (-6400 1600);
DISPLAY INVISIBLE (-6400 1600);
FORCEPROP 0 LAST CDS_SEC 1
J 0
(-6400 1600);
DISPLAY 1.021277 (-6400 1600);
DISPLAY INVISIBLE (-6400 1600);
FORCEPROP 1 LASTPIN (-6450 1525) $PN 1
J 0
(-6445 1487);
DISPLAY 0.489362 (-6445 1487);
PAINT MONO (-6445 1487);
FORCEPROP 1 LASTPIN (-6450 1325) $PN 2
J 0
(-6445 1335);
DISPLAY 0.489362 (-6445 1335);
PAINT MONO (-6445 1335);
FORCEPROP 1 LAST WATTAGE 1/16W
J 0
(-6410 1400);
DISPLAY 0.489362 (-6410 1400);
PAINT SKYBLUE (-6410 1400);
FORCEPROP 1 LAST MATERIAL CHIP
J 0
(-6410 1350);
DISPLAY 0.489362 (-6410 1350);
PAINT SKYBLUE (-6410 1350);
FORCEPROP 1 LAST TOLERANCE 1%
J 0
(-6405 1450);
DISPLAY 0.489362 (-6405 1450);
PAINT SKYBLUE (-6405 1450);
FORCEPROP 1 LAST VALUE 35.7K
J 0
(-6405 1500);
DISPLAY 0.489362 (-6405 1500);
PAINT SKYBLUE (-6405 1500);
FORCEPROP 1 LAST PACK_TYPE 0402LF
J 0
(-6410 1250);
DISPLAY 0.489362 (-6410 1250);
PAINT SKYBLUE (-6410 1250);
FORCEPROP 2 LAST CDS_LIB pure_quanta
J 0
(-6450 1425);
DISPLAY INVISIBLE (-6450 1425);
FORCEPROP 1 LAST PATH I349
J 0
(-6400 1600);
DISPLAY 0.978723 (-6400 1600);
PAINT WHITE (-6400 1600);
DISPLAY INVISIBLE (-6400 1600);
FORCEPROP 1 LAST PART_NUMBER CS33572FB01
J 0
(-6410 1300);
DISPLAY 0.489362 (-6410 1300);
PAINT SKYBLUE (-6410 1300);
DISPLAY INVISIBLE (-6410 1300);
FORCEADD SCONN288_DDR506112002KQ..1
(-6925 3800);
FORCEPROP 1 LAST LOCATION J19
J 0
(-7375 5875);
DISPLAY 0.468085 (-7375 5875);
PAINT SKYBLUE (-7375 5875);
FORCEPROP 0 LAST $SEC 1
J 0
(-7375 6025);
DISPLAY 0.680851 (-7375 6025);
PAINT MONO (-7375 6025);
DISPLAY INVISIBLE (-7375 6025);
FORCEPROP 2 LAST CDS_SEC 1
J 0
(-7375 6025);
DISPLAY 1.021277 (-7375 6025);
DISPLAY INVISIBLE (-7375 6025);
FORCEPROP 0 LASTPIN (-7525 3200) $PN 62
J 2
(-7535 3210);
DISPLAY 0.680851 (-7535 3210);
PAINT MONO (-7535 3210);
FORCEPROP 0 LASTPIN (-7525 5250) $PN 66
J 2
(-7535 5260);
DISPLAY 0.680851 (-7535 5260);
PAINT MONO (-7535 5260);
FORCEPROP 0 LASTPIN (-7525 4850) $PN 76
J 2
(-7535 4860);
DISPLAY 0.680851 (-7535 4860);
PAINT MONO (-7535 4860);
FORCEPROP 0 LASTPIN (-7525 5300) $PN 211
J 2
(-7535 5310);
DISPLAY 0.680851 (-7535 5310);
PAINT MONO (-7535 5310);
FORCEPROP 0 LASTPIN (-7525 4900) $PN 221
J 2
(-7535 4910);
DISPLAY 0.680851 (-7535 4910);
PAINT MONO (-7535 4910);
FORCEPROP 0 LASTPIN (-7525 5350) $PN 68
J 2
(-7535 5360);
DISPLAY 0.680851 (-7535 5360);
PAINT MONO (-7535 5360);
FORCEPROP 0 LASTPIN (-7525 4950) $PN 78
J 2
(-7535 4960);
DISPLAY 0.680851 (-7535 4960);
PAINT MONO (-7535 4960);
FORCEPROP 0 LASTPIN (-7525 5400) $PN 213
J 2
(-7535 5410);
DISPLAY 0.680851 (-7535 5410);
PAINT MONO (-7535 5410);
FORCEPROP 0 LASTPIN (-7525 5000) $PN 223
J 2
(-7535 5010);
DISPLAY 0.680851 (-7535 5010);
PAINT MONO (-7535 5010);
FORCEPROP 0 LASTPIN (-7525 5450) $PN 70
J 2
(-7535 5460);
DISPLAY 0.680851 (-7535 5460);
PAINT MONO (-7535 5460);
FORCEPROP 0 LASTPIN (-7525 5050) $PN 80
J 2
(-7535 5060);
DISPLAY 0.680851 (-7535 5060);
PAINT MONO (-7535 5060);
FORCEPROP 0 LASTPIN (-7525 5500) $PN 215
J 2
(-7535 5510);
DISPLAY 0.680851 (-7535 5510);
PAINT MONO (-7535 5510);
FORCEPROP 0 LASTPIN (-7525 5100) $PN 225
J 2
(-7535 5110);
DISPLAY 0.680851 (-7535 5110);
PAINT MONO (-7535 5110);
FORCEPROP 0 LASTPIN (-7525 5550) $PN 72
J 2
(-7535 5560);
DISPLAY 0.680851 (-7535 5560);
PAINT MONO (-7535 5560);
FORCEPROP 0 LASTPIN (-7525 5150) $PN 82
J 2
(-7535 5160);
DISPLAY 0.680851 (-7535 5160);
PAINT MONO (-7535 5160);
FORCEPROP 0 LASTPIN (-7525 3800) $PN 51
J 2
(-7535 3810);
DISPLAY 0.680851 (-7535 3810);
PAINT MONO (-7535 3810);
FORCEPROP 0 LASTPIN (-7525 3350) $PN 96
J 2
(-7535 3360);
DISPLAY 0.680851 (-7535 3360);
PAINT MONO (-7535 3360);
FORCEPROP 0 LASTPIN (-7525 3850) $PN 53
J 2
(-7535 3860);
DISPLAY 0.680851 (-7535 3860);
PAINT MONO (-7535 3860);
FORCEPROP 0 LASTPIN (-7525 3400) $PN 98
J 2
(-7535 3410);
DISPLAY 0.680851 (-7535 3410);
PAINT MONO (-7535 3410);
FORCEPROP 0 LASTPIN (-7525 3900) $PN 196
J 2
(-7535 3910);
DISPLAY 0.680851 (-7535 3910);
PAINT MONO (-7535 3910);
FORCEPROP 0 LASTPIN (-7525 3450) $PN 241
J 2
(-7535 3460);
DISPLAY 0.680851 (-7535 3460);
PAINT MONO (-7535 3460);
FORCEPROP 0 LASTPIN (-7525 3950) $PN 198
J 2
(-7535 3960);
DISPLAY 0.680851 (-7535 3960);
PAINT MONO (-7535 3960);
FORCEPROP 0 LASTPIN (-7525 3500) $PN 243
J 2
(-7535 3510);
DISPLAY 0.680851 (-7535 3510);
PAINT MONO (-7535 3510);
FORCEPROP 0 LASTPIN (-7525 4000) $PN 58
J 2
(-7535 4010);
DISPLAY 0.680851 (-7535 4010);
PAINT MONO (-7535 4010);
FORCEPROP 0 LASTPIN (-7525 3550) $PN 89
J 2
(-7535 3560);
DISPLAY 0.680851 (-7535 3560);
PAINT MONO (-7535 3560);
FORCEPROP 0 LASTPIN (-7525 4050) $PN 60
J 2
(-7535 4060);
DISPLAY 0.680851 (-7535 4060);
PAINT MONO (-7535 4060);
FORCEPROP 0 LASTPIN (-7525 3600) $PN 91
J 2
(-7535 3610);
DISPLAY 0.680851 (-7535 3610);
PAINT MONO (-7535 3610);
FORCEPROP 0 LASTPIN (-7525 4100) $PN 203
J 2
(-7535 4110);
DISPLAY 0.680851 (-7535 4110);
PAINT MONO (-7535 4110);
FORCEPROP 0 LASTPIN (-7525 3650) $PN 234
J 2
(-7535 3660);
DISPLAY 0.680851 (-7535 3660);
PAINT MONO (-7535 3660);
FORCEPROP 0 LASTPIN (-7525 4150) $PN 205
J 2
(-7535 4160);
DISPLAY 0.680851 (-7535 4160);
PAINT MONO (-7535 4160);
FORCEPROP 0 LASTPIN (-7525 3700) $PN 236
J 2
(-7535 3710);
DISPLAY 0.680851 (-7535 3710);
PAINT MONO (-7535 3710);
FORCEPROP 0 LASTPIN (-7525 4250) $PN 218
J 2
(-7535 4260);
DISPLAY 0.680851 (-7535 4260);
PAINT MONO (-7535 4260);
FORCEPROP 0 LASTPIN (-7525 4300) $PN 217
J 2
(-7535 4310);
DISPLAY 0.680851 (-7535 4310);
PAINT MONO (-7535 4310);
FORCEPROP 0 LASTPIN (-7525 4550) $PN 64
J 2
(-7535 4560);
DISPLAY 0.680851 (-7535 4560);
PAINT MONO (-7535 4560);
FORCEPROP 0 LASTPIN (-7525 4400) $PN 84
J 2
(-7535 4410);
DISPLAY 0.680851 (-7535 4410);
PAINT MONO (-7535 4410);
FORCEPROP 0 LASTPIN (-7525 4600) $PN 209
J 2
(-7535 4610);
DISPLAY 0.680851 (-7535 4610);
PAINT MONO (-7535 4610);
FORCEPROP 0 LASTPIN (-7525 4450) $PN 229
J 2
(-7535 4460);
DISPLAY 0.680851 (-7535 4460);
PAINT MONO (-7535 4460);
FORCEPROP 0 LASTPIN (-6325 4000) $PN 7
J 0
(-6315 4010);
DISPLAY 0.680851 (-6315 4010);
PAINT MONO (-6315 4010);
FORCEPROP 0 LASTPIN (-6325 2350) $PN 100
J 0
(-6315 2360);
DISPLAY 0.680851 (-6315 2360);
PAINT MONO (-6315 2360);
FORCEPROP 0 LASTPIN (-6325 4050) $PN 9
J 0
(-6315 4060);
DISPLAY 0.680851 (-6315 4060);
PAINT MONO (-6315 4060);
FORCEPROP 0 LASTPIN (-6325 2400) $PN 102
J 0
(-6315 2410);
DISPLAY 0.680851 (-6315 2410);
PAINT MONO (-6315 2410);
FORCEPROP 0 LASTPIN (-6325 4100) $PN 152
J 0
(-6315 4110);
DISPLAY 0.680851 (-6315 4110);
PAINT MONO (-6315 4110);
FORCEPROP 0 LASTPIN (-6325 2450) $PN 245
J 0
(-6315 2460);
DISPLAY 0.680851 (-6315 2460);
PAINT MONO (-6315 2460);
FORCEPROP 0 LASTPIN (-6325 4150) $PN 154
J 0
(-6315 4160);
DISPLAY 0.680851 (-6315 4160);
PAINT MONO (-6315 4160);
FORCEPROP 0 LASTPIN (-6325 2500) $PN 247
J 0
(-6315 2510);
DISPLAY 0.680851 (-6315 2510);
PAINT MONO (-6315 2510);
FORCEPROP 0 LASTPIN (-6325 4200) $PN 14
J 0
(-6315 4210);
DISPLAY 0.680851 (-6315 4210);
PAINT MONO (-6315 4210);
FORCEPROP 0 LASTPIN (-6325 2550) $PN 107
J 0
(-6315 2560);
DISPLAY 0.680851 (-6315 2560);
PAINT MONO (-6315 2560);
FORCEPROP 0 LASTPIN (-6325 4250) $PN 16
J 0
(-6315 4260);
DISPLAY 0.680851 (-6315 4260);
PAINT MONO (-6315 4260);
FORCEPROP 0 LASTPIN (-6325 2600) $PN 109
J 0
(-6315 2610);
DISPLAY 0.680851 (-6315 2610);
PAINT MONO (-6315 2610);
FORCEPROP 0 LASTPIN (-6325 4300) $PN 159
J 0
(-6315 4310);
DISPLAY 0.680851 (-6315 4310);
PAINT MONO (-6315 4310);
FORCEPROP 0 LASTPIN (-6325 2650) $PN 252
J 0
(-6315 2660);
DISPLAY 0.680851 (-6315 2660);
PAINT MONO (-6315 2660);
FORCEPROP 0 LASTPIN (-6325 4350) $PN 161
J 0
(-6315 4360);
DISPLAY 0.680851 (-6315 4360);
PAINT MONO (-6315 4360);
FORCEPROP 0 LASTPIN (-6325 2700) $PN 254
J 0
(-6315 2710);
DISPLAY 0.680851 (-6315 2710);
PAINT MONO (-6315 2710);
FORCEPROP 0 LASTPIN (-6325 4400) $PN 18
J 0
(-6315 4410);
DISPLAY 0.680851 (-6315 4410);
PAINT MONO (-6315 4410);
FORCEPROP 0 LASTPIN (-6325 2750) $PN 111
J 0
(-6315 2760);
DISPLAY 0.680851 (-6315 2760);
PAINT MONO (-6315 2760);
FORCEPROP 0 LASTPIN (-6325 4450) $PN 20
J 0
(-6315 4460);
DISPLAY 0.680851 (-6315 4460);
PAINT MONO (-6315 4460);
FORCEPROP 0 LASTPIN (-6325 2800) $PN 113
J 0
(-6315 2810);
DISPLAY 0.680851 (-6315 2810);
PAINT MONO (-6315 2810);
FORCEPROP 0 LASTPIN (-6325 4500) $PN 163
J 0
(-6315 4510);
DISPLAY 0.680851 (-6315 4510);
PAINT MONO (-6315 4510);
FORCEPROP 0 LASTPIN (-6325 2850) $PN 256
J 0
(-6315 2860);
DISPLAY 0.680851 (-6315 2860);
PAINT MONO (-6315 2860);
FORCEPROP 0 LASTPIN (-6325 4550) $PN 165
J 0
(-6315 4560);
DISPLAY 0.680851 (-6315 4560);
PAINT MONO (-6315 4560);
FORCEPROP 0 LASTPIN (-6325 2900) $PN 258
J 0
(-6315 2910);
DISPLAY 0.680851 (-6315 2910);
PAINT MONO (-6315 2910);
FORCEPROP 0 LASTPIN (-6325 4600) $PN 25
J 0
(-6315 4610);
DISPLAY 0.680851 (-6315 4610);
PAINT MONO (-6315 4610);
FORCEPROP 0 LASTPIN (-6325 2950) $PN 118
J 0
(-6315 2960);
DISPLAY 0.680851 (-6315 2960);
PAINT MONO (-6315 2960);
FORCEPROP 0 LASTPIN (-6325 4650) $PN 27
J 0
(-6315 4660);
DISPLAY 0.680851 (-6315 4660);
PAINT MONO (-6315 4660);
FORCEPROP 0 LASTPIN (-6325 3000) $PN 120
J 0
(-6315 3010);
DISPLAY 0.680851 (-6315 3010);
PAINT MONO (-6315 3010);
FORCEPROP 0 LASTPIN (-6325 4700) $PN 170
J 0
(-6315 4710);
DISPLAY 0.680851 (-6315 4710);
PAINT MONO (-6315 4710);
FORCEPROP 0 LASTPIN (-6325 3050) $PN 263
J 0
(-6315 3060);
DISPLAY 0.680851 (-6315 3060);
PAINT MONO (-6315 3060);
FORCEPROP 0 LASTPIN (-6325 4750) $PN 172
J 0
(-6315 4760);
DISPLAY 0.680851 (-6315 4760);
PAINT MONO (-6315 4760);
FORCEPROP 0 LASTPIN (-6325 3100) $PN 265
J 0
(-6315 3110);
DISPLAY 0.680851 (-6315 3110);
PAINT MONO (-6315 3110);
FORCEPROP 0 LASTPIN (-6325 4800) $PN 29
J 0
(-6315 4810);
DISPLAY 0.680851 (-6315 4810);
PAINT MONO (-6315 4810);
FORCEPROP 0 LASTPIN (-6325 3150) $PN 122
J 0
(-6315 3160);
DISPLAY 0.680851 (-6315 3160);
PAINT MONO (-6315 3160);
FORCEPROP 0 LASTPIN (-6325 4850) $PN 31
J 0
(-6315 4860);
DISPLAY 0.680851 (-6315 4860);
PAINT MONO (-6315 4860);
FORCEPROP 0 LASTPIN (-6325 3200) $PN 124
J 0
(-6315 3210);
DISPLAY 0.680851 (-6315 3210);
PAINT MONO (-6315 3210);
FORCEPROP 0 LASTPIN (-6325 4900) $PN 174
J 0
(-6315 4910);
DISPLAY 0.680851 (-6315 4910);
PAINT MONO (-6315 4910);
FORCEPROP 0 LASTPIN (-6325 3250) $PN 267
J 0
(-6315 3260);
DISPLAY 0.680851 (-6315 3260);
PAINT MONO (-6315 3260);
FORCEPROP 0 LASTPIN (-6325 4950) $PN 176
J 0
(-6315 4960);
DISPLAY 0.680851 (-6315 4960);
PAINT MONO (-6315 4960);
FORCEPROP 0 LASTPIN (-6325 3300) $PN 269
J 0
(-6315 3310);
DISPLAY 0.680851 (-6315 3310);
PAINT MONO (-6315 3310);
FORCEPROP 0 LASTPIN (-6325 5000) $PN 36
J 0
(-6315 5010);
DISPLAY 0.680851 (-6315 5010);
PAINT MONO (-6315 5010);
FORCEPROP 0 LASTPIN (-6325 3350) $PN 129
J 0
(-6315 3360);
DISPLAY 0.680851 (-6315 3360);
PAINT MONO (-6315 3360);
FORCEPROP 0 LASTPIN (-6325 5050) $PN 38
J 0
(-6315 5060);
DISPLAY 0.680851 (-6315 5060);
PAINT MONO (-6315 5060);
FORCEPROP 0 LASTPIN (-6325 3400) $PN 131
J 0
(-6315 3410);
DISPLAY 0.680851 (-6315 3410);
PAINT MONO (-6315 3410);
FORCEPROP 0 LASTPIN (-6325 5100) $PN 181
J 0
(-6315 5110);
DISPLAY 0.680851 (-6315 5110);
PAINT MONO (-6315 5110);
FORCEPROP 0 LASTPIN (-6325 3450) $PN 274
J 0
(-6315 3460);
DISPLAY 0.680851 (-6315 3460);
PAINT MONO (-6315 3460);
FORCEPROP 0 LASTPIN (-6325 5150) $PN 183
J 0
(-6315 5160);
DISPLAY 0.680851 (-6315 5160);
PAINT MONO (-6315 5160);
FORCEPROP 0 LASTPIN (-6325 3500) $PN 276
J 0
(-6315 3510);
DISPLAY 0.680851 (-6315 3510);
PAINT MONO (-6315 3510);
FORCEPROP 0 LASTPIN (-6325 5200) $PN 40
J 0
(-6315 5210);
DISPLAY 0.680851 (-6315 5210);
PAINT MONO (-6315 5210);
FORCEPROP 0 LASTPIN (-6325 3550) $PN 133
J 0
(-6315 3560);
DISPLAY 0.680851 (-6315 3560);
PAINT MONO (-6315 3560);
FORCEPROP 0 LASTPIN (-6325 5250) $PN 42
J 0
(-6315 5260);
DISPLAY 0.680851 (-6315 5260);
PAINT MONO (-6315 5260);
FORCEPROP 0 LASTPIN (-6325 3600) $PN 135
J 0
(-6315 3610);
DISPLAY 0.680851 (-6315 3610);
PAINT MONO (-6315 3610);
FORCEPROP 0 LASTPIN (-6325 5300) $PN 185
J 0
(-6315 5310);
DISPLAY 0.680851 (-6315 5310);
PAINT MONO (-6315 5310);
FORCEPROP 0 LASTPIN (-6325 3650) $PN 278
J 0
(-6315 3660);
DISPLAY 0.680851 (-6315 3660);
PAINT MONO (-6315 3660);
FORCEPROP 0 LASTPIN (-6325 5350) $PN 187
J 0
(-6315 5360);
DISPLAY 0.680851 (-6315 5360);
PAINT MONO (-6315 5360);
FORCEPROP 0 LASTPIN (-6325 3700) $PN 280
J 0
(-6315 3710);
DISPLAY 0.680851 (-6315 3710);
PAINT MONO (-6315 3710);
FORCEPROP 0 LASTPIN (-6325 5400) $PN 47
J 0
(-6315 5410);
DISPLAY 0.680851 (-6315 5410);
PAINT MONO (-6315 5410);
FORCEPROP 0 LASTPIN (-6325 3750) $PN 140
J 0
(-6315 3760);
DISPLAY 0.680851 (-6315 3760);
PAINT MONO (-6315 3760);
FORCEPROP 0 LASTPIN (-6325 5450) $PN 49
J 0
(-6315 5460);
DISPLAY 0.680851 (-6315 5460);
PAINT MONO (-6315 5460);
FORCEPROP 0 LASTPIN (-6325 3800) $PN 142
J 0
(-6315 3810);
DISPLAY 0.680851 (-6315 3810);
PAINT MONO (-6315 3810);
FORCEPROP 0 LASTPIN (-6325 5500) $PN 192
J 0
(-6315 5510);
DISPLAY 0.680851 (-6315 5510);
PAINT MONO (-6315 5510);
FORCEPROP 0 LASTPIN (-6325 3850) $PN 285
J 0
(-6315 3860);
DISPLAY 0.680851 (-6315 3860);
PAINT MONO (-6315 3860);
FORCEPROP 0 LASTPIN (-6325 5550) $PN 194
J 0
(-6315 5560);
DISPLAY 0.680851 (-6315 5560);
PAINT MONO (-6315 5560);
FORCEPROP 0 LASTPIN (-6325 3900) $PN 287
J 0
(-6315 3910);
DISPLAY 0.680851 (-6315 3910);
PAINT MONO (-6315 3910);
FORCEPROP 0 LASTPIN (-7525 3050) $PN 148
J 2
(-7535 3060);
DISPLAY 0.680851 (-7535 3060);
PAINT MONO (-7535 3060);
FORCEPROP 0 LASTPIN (-7525 2950) $PN 4
J 2
(-7535 2960);
DISPLAY 0.680851 (-7535 2960);
PAINT MONO (-7535 2960);
FORCEPROP 0 LASTPIN (-7525 3000) $PN 5
J 2
(-7535 3010);
DISPLAY 0.680851 (-7535 3010);
PAINT MONO (-7535 3010);
FORCEPROP 0 LASTPIN (-7525 2150) $PN 86
J 2
(-7535 2160);
DISPLAY 0.680851 (-7535 2160);
PAINT MONO (-7535 2160);
FORCEPROP 0 LASTPIN (-7525 2100) $PN 87
J 2
(-7535 2110);
DISPLAY 0.680851 (-7535 2110);
PAINT MONO (-7535 2110);
FORCEPROP 0 LASTPIN (-7525 4750) $PN 74
J 2
(-7535 4760);
DISPLAY 0.680851 (-7535 4760);
PAINT MONO (-7535 4760);
FORCEPROP 0 LASTPIN (-7525 4700) $PN 227
J 2
(-7535 4710);
DISPLAY 0.680851 (-7535 4710);
PAINT MONO (-7535 4710);
FORCEPROP 0 LASTPIN (-7525 2700) $PN 147
J 2
(-7535 2710);
DISPLAY 0.680851 (-7535 2710);
PAINT MONO (-7535 2710);
FORCEPROP 0 LASTPIN (-7525 3250) $PN 207
J 2
(-7535 3260);
DISPLAY 0.680851 (-7535 3260);
PAINT MONO (-7535 3260);
FORCEPROP 0 LASTPIN (-7525 2300) $PN 2
J 2
(-7535 2310);
DISPLAY 0.680851 (-7535 2310);
PAINT MONO (-7535 2310);
FORCEPROP 0 LASTPIN (-7525 2350) $PN 144
J 2
(-7535 2360);
DISPLAY 0.680851 (-7535 2360);
PAINT MONO (-7535 2360);
FORCEPROP 0 LASTPIN (-7525 2400) $PN 149
J 2
(-7535 2410);
DISPLAY 0.680851 (-7535 2410);
PAINT MONO (-7535 2410);
FORCEPROP 0 LASTPIN (-7525 2450) $PN 150
J 2
(-7535 2460);
DISPLAY 0.680851 (-7535 2460);
PAINT MONO (-7535 2460);
FORCEPROP 0 LASTPIN (-7525 2500) $PN 220
J 2
(-7535 2510);
DISPLAY 0.680851 (-7535 2510);
PAINT MONO (-7535 2510);
FORCEPROP 0 LASTPIN (-7525 2550) $PN 231
J 2
(-7535 2560);
DISPLAY 0.680851 (-7535 2560);
PAINT MONO (-7535 2560);
FORCEPROP 0 LASTPIN (-7525 2600) $PN 232
J 2
(-7535 2610);
DISPLAY 0.680851 (-7535 2610);
PAINT MONO (-7535 2610);
FORCEPROP 0 LASTPIN (-7525 3100) $PN 3
J 2
(-7535 3110);
DISPLAY 0.680851 (-7535 3110);
PAINT MONO (-7535 3110);
FORCEPROP 2 LAST PART_TYPE SMLF
J 0
(-7375 5975);
DISPLAY 1.021277 (-7375 5975);
FORCEPROP 1 LAST MATERIAL IO
J 0
(-7375 5725);
DISPLAY 0.468085 (-7375 5725);
PAINT SKYBLUE (-7375 5725);
FORCEPROP 2 LAST VALUE SCONN288_DDR506112002KQ
J 0
(-7375 5925);
DISPLAY 0.489362 (-7375 5925);
PAINT SKYBLUE (-7375 5925);
FORCEPROP 1 LAST CDS_LMAN_SYM_OUTLINE -450,1900,450,-1850
J 0
(-6925 3800);
DISPLAY 0.468085 (-6925 3800);
PAINT GREEN (-6925 3800);
DISPLAY INVISIBLE (-6925 3800);
FORCEPROP 1 LAST NEEDS_NO_SIZE TRUE
J 0
(-6925 3800);
DISPLAY 0.723404 (-6925 3800);
PAINT GREEN (-6925 3800);
DISPLAY INVISIBLE (-6925 3800);
FORCEPROP 2 LAST CDS_LIB pure_quanta
J 0
(-6925 3800);
DISPLAY INVISIBLE (-6925 3800);
FORCEPROP 1 LAST PATH I350
J 0
(-6925 3800);
DISPLAY 0.723404 (-6925 3800);
PAINT GREEN (-6925 3800);
DISPLAY INVISIBLE (-6925 3800);
FORCEPROP 1 LAST PART_NUMBER DFHST8FS479
J 0
(-7375 5800);
DISPLAY 0.468085 (-7375 5800);
PAINT SKYBLUE (-7375 5800);
DISPLAY INVISIBLE (-7375 5800);
FORCEADD SCONN288_DDR506112002KQ..3
(-1350 3700);
FORCEPROP 1 LAST LOCATION J19
J 0
(-1800 5675);
DISPLAY 0.468085 (-1800 5675);
PAINT SKYBLUE (-1800 5675);
FORCEPROP 0 LAST $SEC 3
J 0
(-1800 5825);
DISPLAY 0.680851 (-1800 5825);
PAINT MONO (-1800 5825);
DISPLAY INVISIBLE (-1800 5825);
FORCEPROP 2 LAST CDS_SEC 3
J 0
(-1800 5825);
DISPLAY 1.021277 (-1800 5825);
DISPLAY INVISIBLE (-1800 5825);
FORCEPROP 0 LASTPIN (-750 2100) $PN G1
J 0
(-740 2110);
DISPLAY 0.680851 (-740 2110);
PAINT MONO (-740 2110);
FORCEPROP 0 LASTPIN (-750 2050) $PN G2
J 0
(-740 2060);
DISPLAY 0.680851 (-740 2060);
PAINT MONO (-740 2060);
FORCEPROP 0 LASTPIN (-750 2000) $PN G3
J 0
(-740 2010);
DISPLAY 0.680851 (-740 2010);
PAINT MONO (-740 2010);
FORCEPROP 0 LASTPIN (-1950 5250) $PN 1
J 2
(-1960 5260);
DISPLAY 0.680851 (-1960 5260);
PAINT MONO (-1960 5260);
FORCEPROP 0 LASTPIN (-1950 5300) $PN 145
J 2
(-1960 5310);
DISPLAY 0.680851 (-1960 5310);
PAINT MONO (-1960 5310);
FORCEPROP 0 LASTPIN (-1950 5350) $PN 146
J 2
(-1960 5360);
DISPLAY 0.680851 (-1960 5360);
PAINT MONO (-1960 5360);
FORCEPROP 0 LASTPIN (-750 2200) $PN 6
J 0
(-740 2210);
DISPLAY 0.680851 (-740 2210);
PAINT MONO (-740 2210);
FORCEPROP 0 LASTPIN (-750 2250) $PN 8
J 0
(-740 2260);
DISPLAY 0.680851 (-740 2260);
PAINT MONO (-740 2260);
FORCEPROP 0 LASTPIN (-750 2300) $PN 10
J 0
(-740 2310);
DISPLAY 0.680851 (-740 2310);
PAINT MONO (-740 2310);
FORCEPROP 0 LASTPIN (-750 2350) $PN 13
J 0
(-740 2360);
DISPLAY 0.680851 (-740 2360);
PAINT MONO (-740 2360);
FORCEPROP 0 LASTPIN (-750 2400) $PN 15
J 0
(-740 2410);
DISPLAY 0.680851 (-740 2410);
PAINT MONO (-740 2410);
FORCEPROP 0 LASTPIN (-750 2450) $PN 17
J 0
(-740 2460);
DISPLAY 0.680851 (-740 2460);
PAINT MONO (-740 2460);
FORCEPROP 0 LASTPIN (-750 2500) $PN 19
J 0
(-740 2510);
DISPLAY 0.680851 (-740 2510);
PAINT MONO (-740 2510);
FORCEPROP 0 LASTPIN (-750 2550) $PN 21
J 0
(-740 2560);
DISPLAY 0.680851 (-740 2560);
PAINT MONO (-740 2560);
FORCEPROP 0 LASTPIN (-750 2600) $PN 24
J 0
(-740 2610);
DISPLAY 0.680851 (-740 2610);
PAINT MONO (-740 2610);
FORCEPROP 0 LASTPIN (-750 2650) $PN 26
J 0
(-740 2660);
DISPLAY 0.680851 (-740 2660);
PAINT MONO (-740 2660);
FORCEPROP 0 LASTPIN (-750 2700) $PN 28
J 0
(-740 2710);
DISPLAY 0.680851 (-740 2710);
PAINT MONO (-740 2710);
FORCEPROP 0 LASTPIN (-750 2750) $PN 30
J 0
(-740 2760);
DISPLAY 0.680851 (-740 2760);
PAINT MONO (-740 2760);
FORCEPROP 0 LASTPIN (-750 2800) $PN 32
J 0
(-740 2810);
DISPLAY 0.680851 (-740 2810);
PAINT MONO (-740 2810);
FORCEPROP 0 LASTPIN (-750 2850) $PN 35
J 0
(-740 2860);
DISPLAY 0.680851 (-740 2860);
PAINT MONO (-740 2860);
FORCEPROP 0 LASTPIN (-750 2900) $PN 37
J 0
(-740 2910);
DISPLAY 0.680851 (-740 2910);
PAINT MONO (-740 2910);
FORCEPROP 0 LASTPIN (-750 2950) $PN 39
J 0
(-740 2960);
DISPLAY 0.680851 (-740 2960);
PAINT MONO (-740 2960);
FORCEPROP 0 LASTPIN (-750 3000) $PN 41
J 0
(-740 3010);
DISPLAY 0.680851 (-740 3010);
PAINT MONO (-740 3010);
FORCEPROP 0 LASTPIN (-750 3050) $PN 43
J 0
(-740 3060);
DISPLAY 0.680851 (-740 3060);
PAINT MONO (-740 3060);
FORCEPROP 0 LASTPIN (-750 3100) $PN 46
J 0
(-740 3110);
DISPLAY 0.680851 (-740 3110);
PAINT MONO (-740 3110);
FORCEPROP 0 LASTPIN (-750 3150) $PN 48
J 0
(-740 3160);
DISPLAY 0.680851 (-740 3160);
PAINT MONO (-740 3160);
FORCEPROP 0 LASTPIN (-750 3200) $PN 50
J 0
(-740 3210);
DISPLAY 0.680851 (-740 3210);
PAINT MONO (-740 3210);
FORCEPROP 0 LASTPIN (-750 3250) $PN 52
J 0
(-740 3260);
DISPLAY 0.680851 (-740 3260);
PAINT MONO (-740 3260);
FORCEPROP 0 LASTPIN (-750 3300) $PN 54
J 0
(-740 3310);
DISPLAY 0.680851 (-740 3310);
PAINT MONO (-740 3310);
FORCEPROP 0 LASTPIN (-750 3350) $PN 57
J 0
(-740 3360);
DISPLAY 0.680851 (-740 3360);
PAINT MONO (-740 3360);
FORCEPROP 0 LASTPIN (-750 3400) $PN 59
J 0
(-740 3410);
DISPLAY 0.680851 (-740 3410);
PAINT MONO (-740 3410);
FORCEPROP 0 LASTPIN (-750 3450) $PN 61
J 0
(-740 3460);
DISPLAY 0.680851 (-740 3460);
PAINT MONO (-740 3460);
FORCEPROP 0 LASTPIN (-750 3500) $PN 63
J 0
(-740 3510);
DISPLAY 0.680851 (-740 3510);
PAINT MONO (-740 3510);
FORCEPROP 0 LASTPIN (-750 3550) $PN 65
J 0
(-740 3560);
DISPLAY 0.680851 (-740 3560);
PAINT MONO (-740 3560);
FORCEPROP 0 LASTPIN (-750 3600) $PN 67
J 0
(-740 3610);
DISPLAY 0.680851 (-740 3610);
PAINT MONO (-740 3610);
FORCEPROP 0 LASTPIN (-750 3650) $PN 69
J 0
(-740 3660);
DISPLAY 0.680851 (-740 3660);
PAINT MONO (-740 3660);
FORCEPROP 0 LASTPIN (-750 3700) $PN 71
J 0
(-740 3710);
DISPLAY 0.680851 (-740 3710);
PAINT MONO (-740 3710);
FORCEPROP 0 LASTPIN (-750 3750) $PN 73
J 0
(-740 3760);
DISPLAY 0.680851 (-740 3760);
PAINT MONO (-740 3760);
FORCEPROP 0 LASTPIN (-750 3800) $PN 75
J 0
(-740 3810);
DISPLAY 0.680851 (-740 3810);
PAINT MONO (-740 3810);
FORCEPROP 0 LASTPIN (-750 3850) $PN 77
J 0
(-740 3860);
DISPLAY 0.680851 (-740 3860);
PAINT MONO (-740 3860);
FORCEPROP 0 LASTPIN (-750 3900) $PN 79
J 0
(-740 3910);
DISPLAY 0.680851 (-740 3910);
PAINT MONO (-740 3910);
FORCEPROP 0 LASTPIN (-750 3950) $PN 81
J 0
(-740 3960);
DISPLAY 0.680851 (-740 3960);
PAINT MONO (-740 3960);
FORCEPROP 0 LASTPIN (-750 4000) $PN 83
J 0
(-740 4010);
DISPLAY 0.680851 (-740 4010);
PAINT MONO (-740 4010);
FORCEPROP 0 LASTPIN (-750 4050) $PN 85
J 0
(-740 4060);
DISPLAY 0.680851 (-740 4060);
PAINT MONO (-740 4060);
FORCEPROP 0 LASTPIN (-750 4100) $PN 88
J 0
(-740 4110);
DISPLAY 0.680851 (-740 4110);
PAINT MONO (-740 4110);
FORCEPROP 0 LASTPIN (-750 4150) $PN 90
J 0
(-740 4160);
DISPLAY 0.680851 (-740 4160);
PAINT MONO (-740 4160);
FORCEPROP 0 LASTPIN (-750 4200) $PN 92
J 0
(-740 4210);
DISPLAY 0.680851 (-740 4210);
PAINT MONO (-740 4210);
FORCEPROP 0 LASTPIN (-750 4250) $PN 95
J 0
(-740 4260);
DISPLAY 0.680851 (-740 4260);
PAINT MONO (-740 4260);
FORCEPROP 0 LASTPIN (-750 4300) $PN 97
J 0
(-740 4310);
DISPLAY 0.680851 (-740 4310);
PAINT MONO (-740 4310);
FORCEPROP 0 LASTPIN (-750 4350) $PN 99
J 0
(-740 4360);
DISPLAY 0.680851 (-740 4360);
PAINT MONO (-740 4360);
FORCEPROP 0 LASTPIN (-750 4400) $PN 101
J 0
(-740 4410);
DISPLAY 0.680851 (-740 4410);
PAINT MONO (-740 4410);
FORCEPROP 0 LASTPIN (-750 4450) $PN 103
J 0
(-740 4460);
DISPLAY 0.680851 (-740 4460);
PAINT MONO (-740 4460);
FORCEPROP 0 LASTPIN (-750 4500) $PN 106
J 0
(-740 4510);
DISPLAY 0.680851 (-740 4510);
PAINT MONO (-740 4510);
FORCEPROP 0 LASTPIN (-750 4550) $PN 108
J 0
(-740 4560);
DISPLAY 0.680851 (-740 4560);
PAINT MONO (-740 4560);
FORCEPROP 0 LASTPIN (-750 4600) $PN 110
J 0
(-740 4610);
DISPLAY 0.680851 (-740 4610);
PAINT MONO (-740 4610);
FORCEPROP 0 LASTPIN (-750 4650) $PN 112
J 0
(-740 4660);
DISPLAY 0.680851 (-740 4660);
PAINT MONO (-740 4660);
FORCEPROP 0 LASTPIN (-750 4700) $PN 114
J 0
(-740 4710);
DISPLAY 0.680851 (-740 4710);
PAINT MONO (-740 4710);
FORCEPROP 0 LASTPIN (-750 4750) $PN 117
J 0
(-740 4760);
DISPLAY 0.680851 (-740 4760);
PAINT MONO (-740 4760);
FORCEPROP 0 LASTPIN (-750 4800) $PN 119
J 0
(-740 4810);
DISPLAY 0.680851 (-740 4810);
PAINT MONO (-740 4810);
FORCEPROP 0 LASTPIN (-750 4850) $PN 121
J 0
(-740 4860);
DISPLAY 0.680851 (-740 4860);
PAINT MONO (-740 4860);
FORCEPROP 0 LASTPIN (-750 4900) $PN 123
J 0
(-740 4910);
DISPLAY 0.680851 (-740 4910);
PAINT MONO (-740 4910);
FORCEPROP 0 LASTPIN (-750 4950) $PN 125
J 0
(-740 4960);
DISPLAY 0.680851 (-740 4960);
PAINT MONO (-740 4960);
FORCEPROP 0 LASTPIN (-750 5000) $PN 128
J 0
(-740 5010);
DISPLAY 0.680851 (-740 5010);
PAINT MONO (-740 5010);
FORCEPROP 0 LASTPIN (-750 5050) $PN 130
J 0
(-740 5060);
DISPLAY 0.680851 (-740 5060);
PAINT MONO (-740 5060);
FORCEPROP 0 LASTPIN (-750 5100) $PN 132
J 0
(-740 5110);
DISPLAY 0.680851 (-740 5110);
PAINT MONO (-740 5110);
FORCEPROP 0 LASTPIN (-750 5150) $PN 134
J 0
(-740 5160);
DISPLAY 0.680851 (-740 5160);
PAINT MONO (-740 5160);
FORCEPROP 0 LASTPIN (-750 5200) $PN 136
J 0
(-740 5210);
DISPLAY 0.680851 (-740 5210);
PAINT MONO (-740 5210);
FORCEPROP 0 LASTPIN (-750 5250) $PN 139
J 0
(-740 5260);
DISPLAY 0.680851 (-740 5260);
PAINT MONO (-740 5260);
FORCEPROP 0 LASTPIN (-750 5300) $PN 141
J 0
(-740 5310);
DISPLAY 0.680851 (-740 5310);
PAINT MONO (-740 5310);
FORCEPROP 0 LASTPIN (-750 5350) $PN 143
J 0
(-740 5360);
DISPLAY 0.680851 (-740 5360);
PAINT MONO (-740 5360);
FORCEPROP 0 LASTPIN (-1950 2100) $PN 151
J 2
(-1960 2110);
DISPLAY 0.680851 (-1960 2110);
PAINT MONO (-1960 2110);
FORCEPROP 0 LASTPIN (-1950 2150) $PN 153
J 2
(-1960 2160);
DISPLAY 0.680851 (-1960 2160);
PAINT MONO (-1960 2160);
FORCEPROP 0 LASTPIN (-1950 2200) $PN 155
J 2
(-1960 2210);
DISPLAY 0.680851 (-1960 2210);
PAINT MONO (-1960 2210);
FORCEPROP 0 LASTPIN (-1950 2250) $PN 158
J 2
(-1960 2260);
DISPLAY 0.680851 (-1960 2260);
PAINT MONO (-1960 2260);
FORCEPROP 0 LASTPIN (-1950 2300) $PN 160
J 2
(-1960 2310);
DISPLAY 0.680851 (-1960 2310);
PAINT MONO (-1960 2310);
FORCEPROP 0 LASTPIN (-1950 2350) $PN 162
J 2
(-1960 2360);
DISPLAY 0.680851 (-1960 2360);
PAINT MONO (-1960 2360);
FORCEPROP 0 LASTPIN (-1950 2400) $PN 164
J 2
(-1960 2410);
DISPLAY 0.680851 (-1960 2410);
PAINT MONO (-1960 2410);
FORCEPROP 0 LASTPIN (-1950 2450) $PN 166
J 2
(-1960 2460);
DISPLAY 0.680851 (-1960 2460);
PAINT MONO (-1960 2460);
FORCEPROP 0 LASTPIN (-1950 2500) $PN 169
J 2
(-1960 2510);
DISPLAY 0.680851 (-1960 2510);
PAINT MONO (-1960 2510);
FORCEPROP 0 LASTPIN (-1950 2550) $PN 171
J 2
(-1960 2560);
DISPLAY 0.680851 (-1960 2560);
PAINT MONO (-1960 2560);
FORCEPROP 0 LASTPIN (-1950 2600) $PN 173
J 2
(-1960 2610);
DISPLAY 0.680851 (-1960 2610);
PAINT MONO (-1960 2610);
FORCEPROP 0 LASTPIN (-1950 2650) $PN 175
J 2
(-1960 2660);
DISPLAY 0.680851 (-1960 2660);
PAINT MONO (-1960 2660);
FORCEPROP 0 LASTPIN (-1950 2700) $PN 177
J 2
(-1960 2710);
DISPLAY 0.680851 (-1960 2710);
PAINT MONO (-1960 2710);
FORCEPROP 0 LASTPIN (-1950 2750) $PN 180
J 2
(-1960 2760);
DISPLAY 0.680851 (-1960 2760);
PAINT MONO (-1960 2760);
FORCEPROP 0 LASTPIN (-1950 2800) $PN 182
J 2
(-1960 2810);
DISPLAY 0.680851 (-1960 2810);
PAINT MONO (-1960 2810);
FORCEPROP 0 LASTPIN (-1950 2850) $PN 184
J 2
(-1960 2860);
DISPLAY 0.680851 (-1960 2860);
PAINT MONO (-1960 2860);
FORCEPROP 0 LASTPIN (-1950 2900) $PN 186
J 2
(-1960 2910);
DISPLAY 0.680851 (-1960 2910);
PAINT MONO (-1960 2910);
FORCEPROP 0 LASTPIN (-1950 2950) $PN 188
J 2
(-1960 2960);
DISPLAY 0.680851 (-1960 2960);
PAINT MONO (-1960 2960);
FORCEPROP 0 LASTPIN (-1950 3000) $PN 191
J 2
(-1960 3010);
DISPLAY 0.680851 (-1960 3010);
PAINT MONO (-1960 3010);
FORCEPROP 0 LASTPIN (-1950 3050) $PN 193
J 2
(-1960 3060);
DISPLAY 0.680851 (-1960 3060);
PAINT MONO (-1960 3060);
FORCEPROP 0 LASTPIN (-1950 3100) $PN 195
J 2
(-1960 3110);
DISPLAY 0.680851 (-1960 3110);
PAINT MONO (-1960 3110);
FORCEPROP 0 LASTPIN (-1950 3150) $PN 197
J 2
(-1960 3160);
DISPLAY 0.680851 (-1960 3160);
PAINT MONO (-1960 3160);
FORCEPROP 0 LASTPIN (-1950 3200) $PN 199
J 2
(-1960 3210);
DISPLAY 0.680851 (-1960 3210);
PAINT MONO (-1960 3210);
FORCEPROP 0 LASTPIN (-1950 3250) $PN 202
J 2
(-1960 3260);
DISPLAY 0.680851 (-1960 3260);
PAINT MONO (-1960 3260);
FORCEPROP 0 LASTPIN (-1950 3300) $PN 204
J 2
(-1960 3310);
DISPLAY 0.680851 (-1960 3310);
PAINT MONO (-1960 3310);
FORCEPROP 0 LASTPIN (-1950 3350) $PN 206
J 2
(-1960 3360);
DISPLAY 0.680851 (-1960 3360);
PAINT MONO (-1960 3360);
FORCEPROP 0 LASTPIN (-1950 3400) $PN 208
J 2
(-1960 3410);
DISPLAY 0.680851 (-1960 3410);
PAINT MONO (-1960 3410);
FORCEPROP 0 LASTPIN (-1950 3450) $PN 210
J 2
(-1960 3460);
DISPLAY 0.680851 (-1960 3460);
PAINT MONO (-1960 3460);
FORCEPROP 0 LASTPIN (-1950 3500) $PN 212
J 2
(-1960 3510);
DISPLAY 0.680851 (-1960 3510);
PAINT MONO (-1960 3510);
FORCEPROP 0 LASTPIN (-1950 3550) $PN 214
J 2
(-1960 3560);
DISPLAY 0.680851 (-1960 3560);
PAINT MONO (-1960 3560);
FORCEPROP 0 LASTPIN (-1950 3600) $PN 216
J 2
(-1960 3610);
DISPLAY 0.680851 (-1960 3610);
PAINT MONO (-1960 3610);
FORCEPROP 0 LASTPIN (-1950 3650) $PN 219
J 2
(-1960 3660);
DISPLAY 0.680851 (-1960 3660);
PAINT MONO (-1960 3660);
FORCEPROP 0 LASTPIN (-1950 3700) $PN 222
J 2
(-1960 3710);
DISPLAY 0.680851 (-1960 3710);
PAINT MONO (-1960 3710);
FORCEPROP 0 LASTPIN (-1950 3750) $PN 224
J 2
(-1960 3760);
DISPLAY 0.680851 (-1960 3760);
PAINT MONO (-1960 3760);
FORCEPROP 0 LASTPIN (-1950 3800) $PN 226
J 2
(-1960 3810);
DISPLAY 0.680851 (-1960 3810);
PAINT MONO (-1960 3810);
FORCEPROP 0 LASTPIN (-1950 3850) $PN 228
J 2
(-1960 3860);
DISPLAY 0.680851 (-1960 3860);
PAINT MONO (-1960 3860);
FORCEPROP 0 LASTPIN (-1950 3900) $PN 230
J 2
(-1960 3910);
DISPLAY 0.680851 (-1960 3910);
PAINT MONO (-1960 3910);
FORCEPROP 0 LASTPIN (-1950 3950) $PN 233
J 2
(-1960 3960);
DISPLAY 0.680851 (-1960 3960);
PAINT MONO (-1960 3960);
FORCEPROP 0 LASTPIN (-1950 4000) $PN 235
J 2
(-1960 4010);
DISPLAY 0.680851 (-1960 4010);
PAINT MONO (-1960 4010);
FORCEPROP 0 LASTPIN (-1950 4050) $PN 237
J 2
(-1960 4060);
DISPLAY 0.680851 (-1960 4060);
PAINT MONO (-1960 4060);
FORCEPROP 0 LASTPIN (-1950 4100) $PN 240
J 2
(-1960 4110);
DISPLAY 0.680851 (-1960 4110);
PAINT MONO (-1960 4110);
FORCEPROP 0 LASTPIN (-1950 4150) $PN 242
J 2
(-1960 4160);
DISPLAY 0.680851 (-1960 4160);
PAINT MONO (-1960 4160);
FORCEPROP 0 LASTPIN (-1950 4200) $PN 244
J 2
(-1960 4210);
DISPLAY 0.680851 (-1960 4210);
PAINT MONO (-1960 4210);
FORCEPROP 0 LASTPIN (-1950 4250) $PN 246
J 2
(-1960 4260);
DISPLAY 0.680851 (-1960 4260);
PAINT MONO (-1960 4260);
FORCEPROP 0 LASTPIN (-1950 4300) $PN 248
J 2
(-1960 4310);
DISPLAY 0.680851 (-1960 4310);
PAINT MONO (-1960 4310);
FORCEPROP 0 LASTPIN (-1950 4350) $PN 251
J 2
(-1960 4360);
DISPLAY 0.680851 (-1960 4360);
PAINT MONO (-1960 4360);
FORCEPROP 0 LASTPIN (-1950 4400) $PN 253
J 2
(-1960 4410);
DISPLAY 0.680851 (-1960 4410);
PAINT MONO (-1960 4410);
FORCEPROP 0 LASTPIN (-1950 4450) $PN 255
J 2
(-1960 4460);
DISPLAY 0.680851 (-1960 4460);
PAINT MONO (-1960 4460);
FORCEPROP 0 LASTPIN (-1950 4500) $PN 257
J 2
(-1960 4510);
DISPLAY 0.680851 (-1960 4510);
PAINT MONO (-1960 4510);
FORCEPROP 0 LASTPIN (-1950 4550) $PN 259
J 2
(-1960 4560);
DISPLAY 0.680851 (-1960 4560);
PAINT MONO (-1960 4560);
FORCEPROP 0 LASTPIN (-1950 4600) $PN 262
J 2
(-1960 4610);
DISPLAY 0.680851 (-1960 4610);
PAINT MONO (-1960 4610);
FORCEPROP 0 LASTPIN (-1950 4650) $PN 264
J 2
(-1960 4660);
DISPLAY 0.680851 (-1960 4660);
PAINT MONO (-1960 4660);
FORCEPROP 0 LASTPIN (-1950 4700) $PN 266
J 2
(-1960 4710);
DISPLAY 0.680851 (-1960 4710);
PAINT MONO (-1960 4710);
FORCEPROP 0 LASTPIN (-1950 4750) $PN 268
J 2
(-1960 4760);
DISPLAY 0.680851 (-1960 4760);
PAINT MONO (-1960 4760);
FORCEPROP 0 LASTPIN (-1950 4800) $PN 270
J 2
(-1960 4810);
DISPLAY 0.680851 (-1960 4810);
PAINT MONO (-1960 4810);
FORCEPROP 0 LASTPIN (-1950 4850) $PN 273
J 2
(-1960 4860);
DISPLAY 0.680851 (-1960 4860);
PAINT MONO (-1960 4860);
FORCEPROP 0 LASTPIN (-1950 4900) $PN 275
J 2
(-1960 4910);
DISPLAY 0.680851 (-1960 4910);
PAINT MONO (-1960 4910);
FORCEPROP 0 LASTPIN (-1950 4950) $PN 277
J 2
(-1960 4960);
DISPLAY 0.680851 (-1960 4960);
PAINT MONO (-1960 4960);
FORCEPROP 0 LASTPIN (-1950 5000) $PN 279
J 2
(-1960 5010);
DISPLAY 0.680851 (-1960 5010);
PAINT MONO (-1960 5010);
FORCEPROP 0 LASTPIN (-1950 5050) $PN 281
J 2
(-1960 5060);
DISPLAY 0.680851 (-1960 5060);
PAINT MONO (-1960 5060);
FORCEPROP 0 LASTPIN (-1950 5100) $PN 284
J 2
(-1960 5110);
DISPLAY 0.680851 (-1960 5110);
PAINT MONO (-1960 5110);
FORCEPROP 0 LASTPIN (-1950 5150) $PN 286
J 2
(-1960 5160);
DISPLAY 0.680851 (-1960 5160);
PAINT MONO (-1960 5160);
FORCEPROP 0 LASTPIN (-1950 5200) $PN 288
J 2
(-1960 5210);
DISPLAY 0.680851 (-1960 5210);
PAINT MONO (-1960 5210);
FORCEPROP 1 LAST MATERIAL IO
J 0
(-1800 5525);
DISPLAY 0.468085 (-1800 5525);
PAINT SKYBLUE (-1800 5525);
FORCEPROP 2 LAST VALUE SCONN288_DDR506112002KQ
J 0
(-1800 5725);
DISPLAY 0.489362 (-1800 5725);
PAINT SKYBLUE (-1800 5725);
FORCEPROP 2 LAST PART_TYPE SMLF
J 0
(-1800 5775);
DISPLAY 1.021277 (-1800 5775);
FORCEPROP 1 LAST CDS_LMAN_SYM_OUTLINE -450,1800,450,-1750
J 0
(-1350 3700);
DISPLAY 0.468085 (-1350 3700);
PAINT GREEN (-1350 3700);
DISPLAY INVISIBLE (-1350 3700);
FORCEPROP 1 LAST NEEDS_NO_SIZE TRUE
J 0
(-1350 3700);
DISPLAY 0.723404 (-1350 3700);
PAINT GREEN (-1350 3700);
DISPLAY INVISIBLE (-1350 3700);
FORCEPROP 2 LAST CDS_LIB pure_quanta
J 0
(-1350 3700);
DISPLAY INVISIBLE (-1350 3700);
FORCEPROP 1 LAST PATH I352
J 0
(-1350 3700);
DISPLAY 0.723404 (-1350 3700);
PAINT GREEN (-1350 3700);
DISPLAY INVISIBLE (-1350 3700);
FORCEPROP 1 LAST PART_NUMBER DFHST8FS479
J 0
(-1800 5600);
DISPLAY 0.468085 (-1800 5600);
PAINT SKYBLUE (-1800 5600);
DISPLAY INVISIBLE (-1800 5600);
FORCEADD OFFPAGE..5
(-8100 3200);
FORCEPROP 2 LAST $XR0 13 
J 0
(-8324 3200);
DISPLAY 0.638298 (-8324 3200);
PAINT MONO (-8324 3200);
FORCEPROP 2 LAST CDS_LIB mstr_standard
J 0
(-8100 3200);
DISPLAY INVISIBLE (-8100 3200);
FORCEPROP 1 LAST OFFPAGE TRUE
J 0
(-7775 3075);
DISPLAY 0.872340 (-7775 3075);
PAINT GREEN (-7775 3075);
DISPLAY INVISIBLE (-7775 3075);
FORCEPROP 1 LAST COMMENT_BODY TRUE
J 0
(-8000 3125);
DISPLAY 0.872340 (-8000 3125);
PAINT GREEN (-8000 3125);
DISPLAY INVISIBLE (-8000 3125);
FORCEPROP 2 LAST PATH I353
J 0
(-8050 3275);
DISPLAY 1.021277 (-8050 3275);
DISPLAY INVISIBLE (-8050 3275);
FORCEADD GND..1
(-8600 3150);
FORCEPROP 3 LASTPIN (-8600 3200) SIG_NAME GND\g
J 0
(-8590 3210);
DISPLAY 0.659574 (-8590 3210);
PAINT MONO (-8590 3210);
DISPLAY INVISIBLE (-8590 3210);
FORCEPROP 2 LAST BOM_COST MEM
J 0
(-8575 3275);
DISPLAY 0.659574 (-8575 3275);
DISPLAY INVISIBLE (-8575 3275);
FORCEPROP 1 LAST SIZE 1B
J 0
(-8525 3100);
DISPLAY 0.723404 (-8525 3100);
PAINT GREEN (-8525 3100);
DISPLAY INVISIBLE (-8525 3100);
FORCEPROP 2 LAST CDS_LIB mstr_symbols
J 0
(-8600 3150);
DISPLAY 0.808511 (-8600 3150);
DISPLAY INVISIBLE (-8600 3150);
FORCEPROP 1 LAST VOLTAGE 0
J 0
(-8620 3245);
DISPLAY 0.829787 (-8620 3245);
PAINT SKYBLUE (-8620 3245);
DISPLAY INVISIBLE (-8620 3245);
FORCEPROP 2 LAST ROOM MEM_EFGH_DECOUPLING_CAPS
J 0
(-8575 3225);
DISPLAY 0.659574 (-8575 3225);
PAINT RED (-8575 3225);
DISPLAY INVISIBLE (-8575 3225);
FORCEPROP 1 LAST BODY_TYPE PLUMBING
J 0
(-8645 3107);
DISPLAY 0.276596 (-8645 3107);
PAINT GREEN (-8645 3107);
DISPLAY INVISIBLE (-8645 3107);
FORCEPROP 1 LAST HDL_POWER GND
J 0
(-8600 3300);
DISPLAY 0.723404 (-8600 3300);
PAINT GREEN (-8600 3300);
DISPLAY INVISIBLE (-8600 3300);
FORCEPROP 1 LAST PATH I361
J 0
(-8525 3150);
DISPLAY 0.872340 (-8525 3150);
PAINT AQUA (-8525 3150);
DISPLAY INVISIBLE (-8525 3150);
FORCEADD Q_CAP..1
R 2
(-8600 3375);
FORCEPROP 1 LAST LOCATION C100
J 2
(-8650 3475);
DISPLAY 0.489362 (-8650 3475);
PAINT SKYBLUE (-8650 3475);
FORCEPROP 0 LAST $SEC 1
J 0
(-8650 3525);
DISPLAY 0.680851 (-8650 3525);
PAINT MONO (-8650 3525);
DISPLAY INVISIBLE (-8650 3525);
FORCEPROP 0 LAST CDS_SEC 1
J 0
(-8650 3525);
DISPLAY 1.021277 (-8650 3525);
DISPLAY INVISIBLE (-8650 3525);
FORCEPROP 1 LASTPIN (-8600 3475) $PN 1
J 2
(-8610 3455);
DISPLAY 0.489362 (-8610 3455);
PAINT MONO (-8610 3455);
FORCEPROP 1 LASTPIN (-8600 3275) $PN 2
J 2
(-8610 3255);
DISPLAY 0.489362 (-8610 3255);
PAINT MONO (-8610 3255);
FORCEPROP 1 LAST PACK_TYPE 0402
J 2
(-8650 3175);
DISPLAY 0.489362 (-8650 3175);
PAINT SKYBLUE (-8650 3175);
FORCEPROP 1 LAST MATERIAL X7R
J 2
(-8650 3275);
DISPLAY 0.489362 (-8650 3275);
PAINT SKYBLUE (-8650 3275);
FORCEPROP 1 LAST VALUE 0.1UF
J 2
(-8650 3425);
DISPLAY 0.489362 (-8650 3425);
PAINT SKYBLUE (-8650 3425);
FORCEPROP 1 LAST VOLTAGE 25V
J 2
(-8650 3375);
DISPLAY 0.489362 (-8650 3375);
PAINT SKYBLUE (-8650 3375);
FORCEPROP 1 LAST TOLERANCE 10%
J 2
(-8650 3325);
DISPLAY 0.489362 (-8650 3325);
PAINT SKYBLUE (-8650 3325);
FORCEPROP 2 LAST CDS_LIB pure_quanta
J 0
(-8600 3375);
DISPLAY INVISIBLE (-8600 3375);
FORCEPROP 0 LAST BOM_COST MEM
J 2
(-8655 3520);
DISPLAY 0.595745 (-8655 3520);
PAINT MONO (-8655 3520);
DISPLAY INVISIBLE (-8655 3520);
FORCEPROP 2 LAST ROOM 
J 2
(-8655 3520);
DISPLAY 0.595745 (-8655 3520);
PAINT RED (-8655 3520);
DISPLAY INVISIBLE (-8655 3520);
FORCEPROP 1 LAST PATH I362
J 2
(-8650 3525);
DISPLAY 0.978723 (-8650 3525);
PAINT WHITE (-8650 3525);
DISPLAY INVISIBLE (-8650 3525);
FORCEPROP 1 LAST PART_NUMBER CH4104K1B00
J 2
(-8650 3225);
DISPLAY 0.489362 (-8650 3225);
PAINT SKYBLUE (-8650 3225);
DISPLAY INVISIBLE (-8650 3225);
FORCEADD Q_RES..2
(-8375 2450);
FORCEPROP 1 LAST LOCATION R92
J 0
(-8330 2575);
DISPLAY 0.489362 (-8330 2575);
PAINT SKYBLUE (-8330 2575);
FORCEPROP 0 LAST $SEC 1
J 0
(-8325 2625);
DISPLAY 0.680851 (-8325 2625);
PAINT MONO (-8325 2625);
DISPLAY INVISIBLE (-8325 2625);
FORCEPROP 0 LAST CDS_SEC 1
J 0
(-8325 2625);
DISPLAY 1.021277 (-8325 2625);
DISPLAY INVISIBLE (-8325 2625);
FORCEPROP 1 LASTPIN (-8375 2550) $PN 1
J 0
(-8370 2512);
DISPLAY 0.489362 (-8370 2512);
PAINT MONO (-8370 2512);
FORCEPROP 1 LASTPIN (-8375 2350) $PN 2
J 0
(-8370 2360);
DISPLAY 0.489362 (-8370 2360);
PAINT MONO (-8370 2360);
FORCEPROP 1 LAST TOLERANCE 1%
J 0
(-8325 2500);
DISPLAY 0.489362 (-8325 2500);
PAINT SKYBLUE (-8325 2500);
FORCEPROP 1 LAST WATTAGE 1/16W
J 0
(-8325 2475);
DISPLAY 0.489362 (-8325 2475);
PAINT SKYBLUE (-8325 2475);
FORCEPROP 1 LAST MATERIAL EMPTY
J 0
(-8325 2450);
DISPLAY 0.489362 (-8325 2450);
PAINT RED (-8325 2450);
FORCEPROP 1 LAST VALUE 1K
J 0
(-8330 2525);
DISPLAY 0.489362 (-8330 2525);
PAINT SKYBLUE (-8330 2525);
FORCEPROP 1 LAST PACK_TYPE 0402LF
J 0
(-8325 2400);
DISPLAY 0.489362 (-8325 2400);
PAINT SKYBLUE (-8325 2400);
FORCEPROP 2 LAST BOM_COST MEM
J 0
(-8325 2625);
DISPLAY 0.808511 (-8325 2625);
DISPLAY INVISIBLE (-8325 2625);
FORCEPROP 2 LAST CDS_LIB pure_quanta
J 0
(-8375 2450);
DISPLAY INVISIBLE (-8375 2450);
FORCEPROP 2 LAST ROOM 
J 0
(-8325 2675);
DISPLAY 0.808511 (-8325 2675);
PAINT RED (-8325 2675);
DISPLAY INVISIBLE (-8325 2675);
FORCEPROP 1 LAST PATH I367
J 0
(-8325 2625);
DISPLAY 0.978723 (-8325 2625);
PAINT WHITE (-8325 2625);
DISPLAY INVISIBLE (-8325 2625);
FORCEPROP 1 LAST PART_NUMBER CS21002FB06
J 0
(-8325 2425);
DISPLAY 0.489362 (-8325 2425);
PAINT SKYBLUE (-8325 2425);
DISPLAY INVISIBLE (-8325 2425);
FORCEADD VCC_CORE..1
(-8375 2625);
FORCEPROP 3 LASTPIN (-8375 2575) SIG_NAME P3V3\g
J 0
(-8365 2585);
DISPLAY 0.659574 (-8365 2585);
PAINT MONO (-8365 2585);
DISPLAY INVISIBLE (-8365 2585);
FORCEPROP 1 LAST HDL_POWER P3V3
J 1
(-8375 2675);
DISPLAY 0.489362 (-8375 2675);
PAINT GREEN (-8375 2675);
FORCEPROP 2 LAST CDS_LIB mstr_symbols
J 0
(-8375 2625);
DISPLAY INVISIBLE (-8375 2625);
FORCEPROP 0 LAST VOLTAGE 3.3
J 0
(-8650 2775);
DISPLAY 1.021277 (-8650 2775);
PAINT SKYBLUE (-8650 2775);
DISPLAY INVISIBLE (-8650 2775);
FORCEPROP 2 LAST ROOM PVCCINFAON_CPU0_CTRL
J 0
(-8375 2725);
DISPLAY 0.808511 (-8375 2725);
PAINT RED (-8375 2725);
DISPLAY INVISIBLE (-8375 2725);
FORCEPROP 1 LAST PATH I368
J 0
(-8325 2650);
DISPLAY 0.872340 (-8325 2650);
PAINT AQUA (-8325 2650);
DISPLAY INVISIBLE (-8325 2650);
FORCEADD Q_RES..1
R 2
(-8500 2300);
FORCEPROP 1 LAST LOCATION R294
J 2
(-8450 2350);
DISPLAY 0.489362 (-8450 2350);
PAINT SKYBLUE (-8450 2350);
FORCEPROP 0 LAST $SEC 1
J 0
(-8450 2400);
DISPLAY 0.680851 (-8450 2400);
PAINT MONO (-8450 2400);
DISPLAY INVISIBLE (-8450 2400);
FORCEPROP 0 LAST CDS_SEC 1
J 0
(-8450 2400);
DISPLAY 1.021277 (-8450 2400);
DISPLAY INVISIBLE (-8450 2400);
FORCEPROP 1 LASTPIN (-8400 2300) $PN 1
J 2
(-8412 2312);
DISPLAY 0.489362 (-8412 2312);
PAINT MONO (-8412 2312);
FORCEPROP 1 LASTPIN (-8600 2300) $PN 2
J 2
(-8562 2312);
DISPLAY 0.489362 (-8562 2312);
PAINT MONO (-8562 2312);
FORCEPROP 1 LAST VALUE 1K
J 0
(-8500 2250);
DISPLAY 0.489362 (-8500 2250);
PAINT SKYBLUE (-8500 2250);
FORCEPROP 1 LAST TOLERANCE 1%
J 2
(-8375 2275);
DISPLAY 0.489362 (-8375 2275);
PAINT SKYBLUE (-8375 2275);
DISPLAY INVISIBLE (-8375 2275);
FORCEPROP 2 LAST BOM_COST MEM
J 0
(-8525 2450);
DISPLAY 0.744681 (-8525 2450);
PAINT WHITE (-8525 2450);
DISPLAY INVISIBLE (-8525 2450);
FORCEPROP 2 LAST CDS_LIB pure_quanta
J 0
(-8500 2300);
DISPLAY INVISIBLE (-8500 2300);
FORCEPROP 1 LAST WATTAGE 1/16W
J 0
(-8425 2225);
DISPLAY 0.489362 (-8425 2225);
PAINT SKYBLUE (-8425 2225);
DISPLAY INVISIBLE (-8425 2225);
FORCEPROP 1 LAST MATERIAL CHIP
J 0
(-8675 2275);
DISPLAY 0.489362 (-8675 2275);
PAINT SKYBLUE (-8675 2275);
DISPLAY INVISIBLE (-8675 2275);
FORCEPROP 1 LAST PACK_TYPE 0402LF
J 0
(-8675 2225);
DISPLAY 0.489362 (-8675 2225);
PAINT SKYBLUE (-8675 2225);
DISPLAY INVISIBLE (-8675 2225);
FORCEPROP 2 LAST ROOM 
J 0
(-8525 2400);
DISPLAY 0.744681 (-8525 2400);
PAINT RED (-8525 2400);
DISPLAY INVISIBLE (-8525 2400);
FORCEPROP 1 LAST PATH I369
J 2
(-8450 2450);
DISPLAY 0.978723 (-8450 2450);
PAINT WHITE (-8450 2450);
DISPLAY INVISIBLE (-8450 2450);
FORCEPROP 1 LAST PART_NUMBER CS21002FB06
J 0
(-8600 2350);
DISPLAY 0.489362 (-8600 2350);
PAINT SKYBLUE (-8600 2350);
DISPLAY INVISIBLE (-8600 2350);
FORCEADD OFFPAGE..6
(-9000 2300);
FORCEPROP 2 LAST $XR4 91 
J 0
(-9339 2264);
DISPLAY 0.638298 (-9339 2264);
PAINT MONO (-9339 2264);
FORCEPROP 2 LAST $XR3 90 
J 0
(-9249 2264);
DISPLAY 0.638298 (-9249 2264);
PAINT MONO (-9249 2264);
FORCEPROP 2 LAST $XR2 88 
J 0
(-9429 2300);
DISPLAY 0.638298 (-9429 2300);
PAINT MONO (-9429 2300);
FORCEPROP 2 LAST $XR1 87 
J 0
(-9339 2300);
DISPLAY 0.638298 (-9339 2300);
PAINT MONO (-9339 2300);
FORCEPROP 2 LAST $XR0 86 
J 0
(-9249 2300);
DISPLAY 0.638298 (-9249 2300);
PAINT MONO (-9249 2300);
FORCEPROP 2 LAST CDS_LIB mstr_standard
J 0
(-9000 2300);
DISPLAY INVISIBLE (-9000 2300);
FORCEPROP 1 LAST OFFPAGE TRUE
J 0
(-8675 2175);
DISPLAY 0.872340 (-8675 2175);
PAINT GREEN (-8675 2175);
DISPLAY INVISIBLE (-8675 2175);
FORCEPROP 1 LAST COMMENT_BODY TRUE
J 0
(-8900 2225);
DISPLAY 0.872340 (-8900 2225);
PAINT GREEN (-8900 2225);
DISPLAY INVISIBLE (-8900 2225);
FORCEPROP 2 LAST PATH I370
J 0
(-8950 2375);
DISPLAY 1.021277 (-8950 2375);
DISPLAY INVISIBLE (-8950 2375);
FORCEADD OFFPAGE..2
(-2700 3575);
FORCEPROP 2 LAST $XR0 13 
J 0
(-2511 3575);
DISPLAY 0.638298 (-2511 3575);
PAINT MONO (-2511 3575);
FORCEPROP 2 LAST CDS_LIB mstr_standard
J 0
(-2700 3575);
DISPLAY 0.723404 (-2700 3575);
PAINT MONO (-2700 3575);
DISPLAY INVISIBLE (-2700 3575);
FORCEPROP 1 LAST OFFPAGE TRUE
J 0
(-2375 3450);
DISPLAY 0.723404 (-2375 3450);
PAINT GREEN (-2375 3450);
DISPLAY INVISIBLE (-2375 3450);
FORCEPROP 1 LAST COMMENT_BODY TRUE
J 0
(-2745 3480);
DISPLAY 0.872340 (-2745 3480);
PAINT GREEN (-2745 3480);
DISPLAY INVISIBLE (-2745 3480);
FORCEPROP 2 LAST PATH I371
J 0
(-2500 3625);
DISPLAY 0.680851 (-2500 3625);
DISPLAY INVISIBLE (-2500 3625);
FORCEADD OFFPAGE..2
(-2700 3625);
FORCEPROP 2 LAST $XR0 13 
J 0
(-2511 3625);
DISPLAY 0.638298 (-2511 3625);
PAINT MONO (-2511 3625);
FORCEPROP 2 LAST CDS_LIB mstr_standard
J 0
(-2700 3625);
DISPLAY 0.723404 (-2700 3625);
PAINT MONO (-2700 3625);
DISPLAY INVISIBLE (-2700 3625);
FORCEPROP 1 LAST OFFPAGE TRUE
J 0
(-2375 3500);
DISPLAY 0.723404 (-2375 3500);
PAINT GREEN (-2375 3500);
DISPLAY INVISIBLE (-2375 3500);
FORCEPROP 1 LAST COMMENT_BODY TRUE
J 0
(-2745 3530);
DISPLAY 0.872340 (-2745 3530);
PAINT GREEN (-2745 3530);
DISPLAY INVISIBLE (-2745 3530);
FORCEPROP 2 LAST PATH I372
J 0
(-2500 3675);
DISPLAY 0.680851 (-2500 3675);
DISPLAY INVISIBLE (-2500 3675);
FORCEADD OFFPAGE..2
(-2700 4625);
FORCEPROP 2 LAST $XR0 13 
J 0
(-2511 4625);
DISPLAY 0.638298 (-2511 4625);
PAINT MONO (-2511 4625);
FORCEPROP 2 LAST CDS_LIB mstr_standard
J 0
(-2700 4625);
DISPLAY 0.723404 (-2700 4625);
PAINT MONO (-2700 4625);
DISPLAY INVISIBLE (-2700 4625);
FORCEPROP 1 LAST OFFPAGE TRUE
J 0
(-2375 4500);
DISPLAY 0.723404 (-2375 4500);
PAINT GREEN (-2375 4500);
DISPLAY INVISIBLE (-2375 4500);
FORCEPROP 1 LAST COMMENT_BODY TRUE
J 0
(-2745 4530);
DISPLAY 0.872340 (-2745 4530);
PAINT GREEN (-2745 4530);
DISPLAY INVISIBLE (-2745 4530);
FORCEPROP 2 LAST PATH I373
J 0
(-2500 4675);
DISPLAY 0.680851 (-2500 4675);
DISPLAY INVISIBLE (-2500 4675);
FORCEADD OFFPAGE..2
(-2700 4675);
FORCEPROP 2 LAST $XR0 13 
J 0
(-2511 4675);
DISPLAY 0.638298 (-2511 4675);
PAINT MONO (-2511 4675);
FORCEPROP 2 LAST CDS_LIB mstr_standard
J 0
(-2700 4675);
DISPLAY 0.723404 (-2700 4675);
PAINT MONO (-2700 4675);
DISPLAY INVISIBLE (-2700 4675);
FORCEPROP 1 LAST OFFPAGE TRUE
J 0
(-2375 4550);
DISPLAY 0.723404 (-2375 4550);
PAINT GREEN (-2375 4550);
DISPLAY INVISIBLE (-2375 4550);
FORCEPROP 1 LAST COMMENT_BODY TRUE
J 0
(-2745 4580);
DISPLAY 0.872340 (-2745 4580);
PAINT GREEN (-2745 4580);
DISPLAY INVISIBLE (-2745 4580);
FORCEPROP 2 LAST PATH I374
J 0
(-2500 4725);
DISPLAY 0.680851 (-2500 4725);
DISPLAY INVISIBLE (-2500 4725);
FORCEADD TAP..1
(-3500 4575);
FORCEPROP 3 LASTPIN (-3550 4575) SIG_NAME M_D_CPU0_SA_DQS_DN<9>
J 0
(-3540 4585);
DISPLAY 0.659574 (-3540 4585);
PAINT MONO (-3540 4585);
DISPLAY INVISIBLE (-3540 4585);
FORCEPROP 1 LASTPIN (-3550 4575) BN 9
J 0
(-3562 4583);
DISPLAY 0.489362 (-3562 4583);
PAINT GREEN (-3562 4583);
FORCEPROP 2 LAST CDS_LIB mstr_standard
J 0
(-3500 4575);
DISPLAY 0.723404 (-3500 4575);
PAINT MONO (-3500 4575);
DISPLAY INVISIBLE (-3500 4575);
FORCEPROP 1 LAST BODY_TYPE PLUMBING
J 0
(-3500 4625);
DISPLAY 0.872340 (-3500 4625);
PAINT GREEN (-3500 4625);
DISPLAY INVISIBLE (-3500 4625);
FORCEPROP 1 LAST HDL_TAP TRUE
J 0
(-3175 4450);
DISPLAY 0.872340 (-3175 4450);
DISPLAY INVISIBLE (-3175 4450);
FORCEPROP 1 LAST PATH I375
J 0
(-3502 4575);
DISPLAY 0.872340 (-3502 4575);
PAINT GREEN (-3502 4575);
DISPLAY INVISIBLE (-3502 4575);
FORCEADD TAP..1
(-3500 4475);
FORCEPROP 3 LASTPIN (-3550 4475) SIG_NAME M_D_CPU0_SA_DQS_DN<8>
J 0
(-3540 4485);
DISPLAY 0.659574 (-3540 4485);
PAINT MONO (-3540 4485);
DISPLAY INVISIBLE (-3540 4485);
FORCEPROP 1 LASTPIN (-3550 4475) BN 8
J 0
(-3562 4483);
DISPLAY 0.489362 (-3562 4483);
PAINT GREEN (-3562 4483);
FORCEPROP 2 LAST CDS_LIB mstr_standard
J 0
(-3500 4475);
DISPLAY 0.723404 (-3500 4475);
PAINT MONO (-3500 4475);
DISPLAY INVISIBLE (-3500 4475);
FORCEPROP 1 LAST BODY_TYPE PLUMBING
J 0
(-3500 4525);
DISPLAY 0.872340 (-3500 4525);
PAINT GREEN (-3500 4525);
DISPLAY INVISIBLE (-3500 4525);
FORCEPROP 1 LAST HDL_TAP TRUE
J 0
(-3175 4350);
DISPLAY 0.872340 (-3175 4350);
DISPLAY INVISIBLE (-3175 4350);
FORCEPROP 1 LAST PATH I376
J 0
(-3502 4475);
DISPLAY 0.872340 (-3502 4475);
PAINT GREEN (-3502 4475);
DISPLAY INVISIBLE (-3502 4475);
FORCEADD TAP..1
(-3500 4375);
FORCEPROP 3 LASTPIN (-3550 4375) SIG_NAME M_D_CPU0_SA_DQS_DN<7>
J 0
(-3540 4385);
DISPLAY 0.659574 (-3540 4385);
PAINT MONO (-3540 4385);
DISPLAY INVISIBLE (-3540 4385);
FORCEPROP 1 LASTPIN (-3550 4375) BN 7
J 0
(-3562 4383);
DISPLAY 0.489362 (-3562 4383);
PAINT GREEN (-3562 4383);
FORCEPROP 2 LAST CDS_LIB mstr_standard
J 0
(-3500 4375);
DISPLAY 0.723404 (-3500 4375);
PAINT MONO (-3500 4375);
DISPLAY INVISIBLE (-3500 4375);
FORCEPROP 1 LAST BODY_TYPE PLUMBING
J 0
(-3500 4425);
DISPLAY 0.872340 (-3500 4425);
PAINT GREEN (-3500 4425);
DISPLAY INVISIBLE (-3500 4425);
FORCEPROP 1 LAST HDL_TAP TRUE
J 0
(-3175 4250);
DISPLAY 0.872340 (-3175 4250);
DISPLAY INVISIBLE (-3175 4250);
FORCEPROP 1 LAST PATH I377
J 0
(-3502 4375);
DISPLAY 0.872340 (-3502 4375);
PAINT GREEN (-3502 4375);
DISPLAY INVISIBLE (-3502 4375);
FORCEADD TAP..1
(-3500 4275);
FORCEPROP 3 LASTPIN (-3550 4275) SIG_NAME M_D_CPU0_SA_DQS_DN<6>
J 0
(-3540 4285);
DISPLAY 0.659574 (-3540 4285);
PAINT MONO (-3540 4285);
DISPLAY INVISIBLE (-3540 4285);
FORCEPROP 1 LASTPIN (-3550 4275) BN 6
J 0
(-3562 4283);
DISPLAY 0.489362 (-3562 4283);
PAINT GREEN (-3562 4283);
FORCEPROP 2 LAST CDS_LIB mstr_standard
J 0
(-3500 4275);
DISPLAY 0.723404 (-3500 4275);
PAINT MONO (-3500 4275);
DISPLAY INVISIBLE (-3500 4275);
FORCEPROP 1 LAST BODY_TYPE PLUMBING
J 0
(-3500 4325);
DISPLAY 0.872340 (-3500 4325);
PAINT GREEN (-3500 4325);
DISPLAY INVISIBLE (-3500 4325);
FORCEPROP 1 LAST HDL_TAP TRUE
J 0
(-3175 4150);
DISPLAY 0.872340 (-3175 4150);
DISPLAY INVISIBLE (-3175 4150);
FORCEPROP 1 LAST PATH I378
J 0
(-3502 4275);
DISPLAY 0.872340 (-3502 4275);
PAINT GREEN (-3502 4275);
DISPLAY INVISIBLE (-3502 4275);
FORCEADD TAP..1
(-3700 4525);
FORCEPROP 3 LASTPIN (-3750 4525) SIG_NAME M_D_CPU0_SA_DQS_DP<8>
J 0
(-3740 4535);
DISPLAY 0.659574 (-3740 4535);
PAINT MONO (-3740 4535);
DISPLAY INVISIBLE (-3740 4535);
FORCEPROP 1 LASTPIN (-3750 4525) BN 8
J 0
(-3762 4533);
DISPLAY 0.489362 (-3762 4533);
PAINT GREEN (-3762 4533);
FORCEPROP 2 LAST CDS_LIB mstr_standard
J 0
(-3700 4525);
DISPLAY 0.723404 (-3700 4525);
PAINT MONO (-3700 4525);
DISPLAY INVISIBLE (-3700 4525);
FORCEPROP 1 LAST BODY_TYPE PLUMBING
J 0
(-3700 4575);
DISPLAY 0.872340 (-3700 4575);
PAINT GREEN (-3700 4575);
DISPLAY INVISIBLE (-3700 4575);
FORCEPROP 1 LAST HDL_TAP TRUE
J 0
(-3375 4400);
DISPLAY 0.872340 (-3375 4400);
DISPLAY INVISIBLE (-3375 4400);
FORCEPROP 1 LAST PATH I379
J 0
(-3702 4525);
DISPLAY 0.872340 (-3702 4525);
PAINT GREEN (-3702 4525);
DISPLAY INVISIBLE (-3702 4525);
FORCEADD TAP..1
(-3700 4625);
FORCEPROP 3 LASTPIN (-3750 4625) SIG_NAME M_D_CPU0_SA_DQS_DP<9>
J 0
(-3740 4635);
DISPLAY 0.659574 (-3740 4635);
PAINT MONO (-3740 4635);
DISPLAY INVISIBLE (-3740 4635);
FORCEPROP 1 LASTPIN (-3750 4625) BN 9
J 0
(-3762 4633);
DISPLAY 0.489362 (-3762 4633);
PAINT GREEN (-3762 4633);
FORCEPROP 2 LAST CDS_LIB mstr_standard
J 0
(-3700 4625);
DISPLAY 0.723404 (-3700 4625);
PAINT MONO (-3700 4625);
DISPLAY INVISIBLE (-3700 4625);
FORCEPROP 1 LAST BODY_TYPE PLUMBING
J 0
(-3700 4675);
DISPLAY 0.872340 (-3700 4675);
PAINT GREEN (-3700 4675);
DISPLAY INVISIBLE (-3700 4675);
FORCEPROP 1 LAST HDL_TAP TRUE
J 0
(-3375 4500);
DISPLAY 0.872340 (-3375 4500);
DISPLAY INVISIBLE (-3375 4500);
FORCEPROP 1 LAST PATH I380
J 0
(-3702 4625);
DISPLAY 0.872340 (-3702 4625);
PAINT GREEN (-3702 4625);
DISPLAY INVISIBLE (-3702 4625);
FORCEADD TAP..1
(-3700 4425);
FORCEPROP 3 LASTPIN (-3750 4425) SIG_NAME M_D_CPU0_SA_DQS_DP<7>
J 0
(-3740 4435);
DISPLAY 0.659574 (-3740 4435);
PAINT MONO (-3740 4435);
DISPLAY INVISIBLE (-3740 4435);
FORCEPROP 1 LASTPIN (-3750 4425) BN 7
J 0
(-3762 4433);
DISPLAY 0.489362 (-3762 4433);
PAINT GREEN (-3762 4433);
FORCEPROP 2 LAST CDS_LIB mstr_standard
J 0
(-3700 4425);
DISPLAY 0.723404 (-3700 4425);
PAINT MONO (-3700 4425);
DISPLAY INVISIBLE (-3700 4425);
FORCEPROP 1 LAST BODY_TYPE PLUMBING
J 0
(-3700 4475);
DISPLAY 0.872340 (-3700 4475);
PAINT GREEN (-3700 4475);
DISPLAY INVISIBLE (-3700 4475);
FORCEPROP 1 LAST HDL_TAP TRUE
J 0
(-3375 4300);
DISPLAY 0.872340 (-3375 4300);
DISPLAY INVISIBLE (-3375 4300);
FORCEPROP 1 LAST PATH I381
J 0
(-3702 4425);
DISPLAY 0.872340 (-3702 4425);
PAINT GREEN (-3702 4425);
DISPLAY INVISIBLE (-3702 4425);
FORCEADD TAP..1
(-3700 4325);
FORCEPROP 3 LASTPIN (-3750 4325) SIG_NAME M_D_CPU0_SA_DQS_DP<6>
J 0
(-3740 4335);
DISPLAY 0.659574 (-3740 4335);
PAINT MONO (-3740 4335);
DISPLAY INVISIBLE (-3740 4335);
FORCEPROP 1 LASTPIN (-3750 4325) BN 6
J 0
(-3762 4333);
DISPLAY 0.489362 (-3762 4333);
PAINT GREEN (-3762 4333);
FORCEPROP 2 LAST CDS_LIB mstr_standard
J 0
(-3700 4325);
DISPLAY 0.723404 (-3700 4325);
PAINT MONO (-3700 4325);
DISPLAY INVISIBLE (-3700 4325);
FORCEPROP 1 LAST BODY_TYPE PLUMBING
J 0
(-3700 4375);
DISPLAY 0.872340 (-3700 4375);
PAINT GREEN (-3700 4375);
DISPLAY INVISIBLE (-3700 4375);
FORCEPROP 1 LAST HDL_TAP TRUE
J 0
(-3375 4200);
DISPLAY 0.872340 (-3375 4200);
DISPLAY INVISIBLE (-3375 4200);
FORCEPROP 1 LAST PATH I382
J 0
(-3702 4325);
DISPLAY 0.872340 (-3702 4325);
PAINT GREEN (-3702 4325);
DISPLAY INVISIBLE (-3702 4325);
FORCEADD TAP..1
(-3500 4175);
FORCEPROP 3 LASTPIN (-3550 4175) SIG_NAME M_D_CPU0_SA_DQS_DN<5>
J 0
(-3540 4185);
DISPLAY 0.659574 (-3540 4185);
PAINT MONO (-3540 4185);
DISPLAY INVISIBLE (-3540 4185);
FORCEPROP 1 LASTPIN (-3550 4175) BN 5
J 0
(-3562 4183);
DISPLAY 0.489362 (-3562 4183);
PAINT GREEN (-3562 4183);
FORCEPROP 2 LAST CDS_LIB mstr_standard
J 0
(-3500 4175);
DISPLAY 0.723404 (-3500 4175);
PAINT MONO (-3500 4175);
DISPLAY INVISIBLE (-3500 4175);
FORCEPROP 1 LAST BODY_TYPE PLUMBING
J 0
(-3500 4225);
DISPLAY 0.872340 (-3500 4225);
PAINT GREEN (-3500 4225);
DISPLAY INVISIBLE (-3500 4225);
FORCEPROP 1 LAST HDL_TAP TRUE
J 0
(-3175 4050);
DISPLAY 0.872340 (-3175 4050);
DISPLAY INVISIBLE (-3175 4050);
FORCEPROP 1 LAST PATH I383
J 0
(-3502 4175);
DISPLAY 0.872340 (-3502 4175);
PAINT GREEN (-3502 4175);
DISPLAY INVISIBLE (-3502 4175);
FORCEADD TAP..1
(-3500 4075);
FORCEPROP 3 LASTPIN (-3550 4075) SIG_NAME M_D_CPU0_SA_DQS_DN<4>
J 0
(-3540 4085);
DISPLAY 0.659574 (-3540 4085);
PAINT MONO (-3540 4085);
DISPLAY INVISIBLE (-3540 4085);
FORCEPROP 1 LASTPIN (-3550 4075) BN 4
J 0
(-3562 4083);
DISPLAY 0.489362 (-3562 4083);
PAINT GREEN (-3562 4083);
FORCEPROP 2 LAST CDS_LIB mstr_standard
J 0
(-3500 4075);
DISPLAY 0.723404 (-3500 4075);
PAINT MONO (-3500 4075);
DISPLAY INVISIBLE (-3500 4075);
FORCEPROP 1 LAST BODY_TYPE PLUMBING
J 0
(-3500 4125);
DISPLAY 0.872340 (-3500 4125);
PAINT GREEN (-3500 4125);
DISPLAY INVISIBLE (-3500 4125);
FORCEPROP 1 LAST HDL_TAP TRUE
J 0
(-3175 3950);
DISPLAY 0.872340 (-3175 3950);
DISPLAY INVISIBLE (-3175 3950);
FORCEPROP 1 LAST PATH I384
J 0
(-3502 4075);
DISPLAY 0.872340 (-3502 4075);
PAINT GREEN (-3502 4075);
DISPLAY INVISIBLE (-3502 4075);
FORCEADD TAP..1
(-3500 3975);
FORCEPROP 3 LASTPIN (-3550 3975) SIG_NAME M_D_CPU0_SA_DQS_DN<3>
J 0
(-3540 3985);
DISPLAY 0.659574 (-3540 3985);
PAINT MONO (-3540 3985);
DISPLAY INVISIBLE (-3540 3985);
FORCEPROP 1 LASTPIN (-3550 3975) BN 3
J 0
(-3562 3983);
DISPLAY 0.489362 (-3562 3983);
PAINT GREEN (-3562 3983);
FORCEPROP 2 LAST CDS_LIB mstr_standard
J 0
(-3500 3975);
DISPLAY 0.723404 (-3500 3975);
PAINT MONO (-3500 3975);
DISPLAY INVISIBLE (-3500 3975);
FORCEPROP 1 LAST BODY_TYPE PLUMBING
J 0
(-3500 4025);
DISPLAY 0.872340 (-3500 4025);
PAINT GREEN (-3500 4025);
DISPLAY INVISIBLE (-3500 4025);
FORCEPROP 1 LAST HDL_TAP TRUE
J 0
(-3175 3850);
DISPLAY 0.872340 (-3175 3850);
DISPLAY INVISIBLE (-3175 3850);
FORCEPROP 1 LAST PATH I385
J 0
(-3502 3975);
DISPLAY 0.872340 (-3502 3975);
PAINT GREEN (-3502 3975);
DISPLAY INVISIBLE (-3502 3975);
FORCEADD TAP..1
(-3500 3875);
FORCEPROP 3 LASTPIN (-3550 3875) SIG_NAME M_D_CPU0_SA_DQS_DN<2>
J 0
(-3540 3885);
DISPLAY 0.659574 (-3540 3885);
PAINT MONO (-3540 3885);
DISPLAY INVISIBLE (-3540 3885);
FORCEPROP 1 LASTPIN (-3550 3875) BN 2
J 0
(-3562 3883);
DISPLAY 0.489362 (-3562 3883);
PAINT GREEN (-3562 3883);
FORCEPROP 2 LAST CDS_LIB mstr_standard
J 0
(-3500 3875);
DISPLAY 0.723404 (-3500 3875);
PAINT MONO (-3500 3875);
DISPLAY INVISIBLE (-3500 3875);
FORCEPROP 1 LAST BODY_TYPE PLUMBING
J 0
(-3500 3925);
DISPLAY 0.872340 (-3500 3925);
PAINT GREEN (-3500 3925);
DISPLAY INVISIBLE (-3500 3925);
FORCEPROP 1 LAST HDL_TAP TRUE
J 0
(-3175 3750);
DISPLAY 0.872340 (-3175 3750);
DISPLAY INVISIBLE (-3175 3750);
FORCEPROP 1 LAST PATH I386
J 0
(-3502 3875);
DISPLAY 0.872340 (-3502 3875);
PAINT GREEN (-3502 3875);
DISPLAY INVISIBLE (-3502 3875);
FORCEADD TAP..1
(-3500 3775);
FORCEPROP 3 LASTPIN (-3550 3775) SIG_NAME M_D_CPU0_SA_DQS_DN<1>
J 0
(-3540 3785);
DISPLAY 0.659574 (-3540 3785);
PAINT MONO (-3540 3785);
DISPLAY INVISIBLE (-3540 3785);
FORCEPROP 1 LASTPIN (-3550 3775) BN 1
J 0
(-3562 3783);
DISPLAY 0.489362 (-3562 3783);
PAINT GREEN (-3562 3783);
FORCEPROP 2 LAST CDS_LIB mstr_standard
J 0
(-3500 3775);
DISPLAY 0.723404 (-3500 3775);
PAINT MONO (-3500 3775);
DISPLAY INVISIBLE (-3500 3775);
FORCEPROP 1 LAST BODY_TYPE PLUMBING
J 0
(-3500 3825);
DISPLAY 0.872340 (-3500 3825);
PAINT GREEN (-3500 3825);
DISPLAY INVISIBLE (-3500 3825);
FORCEPROP 1 LAST HDL_TAP TRUE
J 0
(-3175 3650);
DISPLAY 0.872340 (-3175 3650);
DISPLAY INVISIBLE (-3175 3650);
FORCEPROP 1 LAST PATH I387
J 0
(-3502 3775);
DISPLAY 0.872340 (-3502 3775);
PAINT GREEN (-3502 3775);
DISPLAY INVISIBLE (-3502 3775);
FORCEADD TAP..1
(-3700 4225);
FORCEPROP 3 LASTPIN (-3750 4225) SIG_NAME M_D_CPU0_SA_DQS_DP<5>
J 0
(-3740 4235);
DISPLAY 0.659574 (-3740 4235);
PAINT MONO (-3740 4235);
DISPLAY INVISIBLE (-3740 4235);
FORCEPROP 1 LASTPIN (-3750 4225) BN 5
J 0
(-3762 4233);
DISPLAY 0.489362 (-3762 4233);
PAINT GREEN (-3762 4233);
FORCEPROP 2 LAST CDS_LIB mstr_standard
J 0
(-3700 4225);
DISPLAY 0.723404 (-3700 4225);
PAINT MONO (-3700 4225);
DISPLAY INVISIBLE (-3700 4225);
FORCEPROP 1 LAST BODY_TYPE PLUMBING
J 0
(-3700 4275);
DISPLAY 0.872340 (-3700 4275);
PAINT GREEN (-3700 4275);
DISPLAY INVISIBLE (-3700 4275);
FORCEPROP 1 LAST HDL_TAP TRUE
J 0
(-3375 4100);
DISPLAY 0.872340 (-3375 4100);
DISPLAY INVISIBLE (-3375 4100);
FORCEPROP 1 LAST PATH I388
J 0
(-3702 4225);
DISPLAY 0.872340 (-3702 4225);
PAINT GREEN (-3702 4225);
DISPLAY INVISIBLE (-3702 4225);
FORCEADD TAP..1
(-3700 4125);
FORCEPROP 3 LASTPIN (-3750 4125) SIG_NAME M_D_CPU0_SA_DQS_DP<4>
J 0
(-3740 4135);
DISPLAY 0.659574 (-3740 4135);
PAINT MONO (-3740 4135);
DISPLAY INVISIBLE (-3740 4135);
FORCEPROP 1 LASTPIN (-3750 4125) BN 4
J 0
(-3762 4133);
DISPLAY 0.489362 (-3762 4133);
PAINT GREEN (-3762 4133);
FORCEPROP 2 LAST CDS_LIB mstr_standard
J 0
(-3700 4125);
DISPLAY 0.723404 (-3700 4125);
PAINT MONO (-3700 4125);
DISPLAY INVISIBLE (-3700 4125);
FORCEPROP 1 LAST BODY_TYPE PLUMBING
J 0
(-3700 4175);
DISPLAY 0.872340 (-3700 4175);
PAINT GREEN (-3700 4175);
DISPLAY INVISIBLE (-3700 4175);
FORCEPROP 1 LAST HDL_TAP TRUE
J 0
(-3375 4000);
DISPLAY 0.872340 (-3375 4000);
DISPLAY INVISIBLE (-3375 4000);
FORCEPROP 1 LAST PATH I389
J 0
(-3702 4125);
DISPLAY 0.872340 (-3702 4125);
PAINT GREEN (-3702 4125);
DISPLAY INVISIBLE (-3702 4125);
FORCEADD TAP..1
(-3700 4025);
FORCEPROP 3 LASTPIN (-3750 4025) SIG_NAME M_D_CPU0_SA_DQS_DP<3>
J 0
(-3740 4035);
DISPLAY 0.659574 (-3740 4035);
PAINT MONO (-3740 4035);
DISPLAY INVISIBLE (-3740 4035);
FORCEPROP 1 LASTPIN (-3750 4025) BN 3
J 0
(-3762 4033);
DISPLAY 0.489362 (-3762 4033);
PAINT GREEN (-3762 4033);
FORCEPROP 2 LAST CDS_LIB mstr_standard
J 0
(-3700 4025);
DISPLAY 0.723404 (-3700 4025);
PAINT MONO (-3700 4025);
DISPLAY INVISIBLE (-3700 4025);
FORCEPROP 1 LAST BODY_TYPE PLUMBING
J 0
(-3700 4075);
DISPLAY 0.872340 (-3700 4075);
PAINT GREEN (-3700 4075);
DISPLAY INVISIBLE (-3700 4075);
FORCEPROP 1 LAST HDL_TAP TRUE
J 0
(-3375 3900);
DISPLAY 0.872340 (-3375 3900);
DISPLAY INVISIBLE (-3375 3900);
FORCEPROP 1 LAST PATH I390
J 0
(-3702 4025);
DISPLAY 0.872340 (-3702 4025);
PAINT GREEN (-3702 4025);
DISPLAY INVISIBLE (-3702 4025);
FORCEADD TAP..1
(-3700 3925);
FORCEPROP 3 LASTPIN (-3750 3925) SIG_NAME M_D_CPU0_SA_DQS_DP<2>
J 0
(-3740 3935);
DISPLAY 0.659574 (-3740 3935);
PAINT MONO (-3740 3935);
DISPLAY INVISIBLE (-3740 3935);
FORCEPROP 1 LASTPIN (-3750 3925) BN 2
J 0
(-3762 3933);
DISPLAY 0.489362 (-3762 3933);
PAINT GREEN (-3762 3933);
FORCEPROP 2 LAST CDS_LIB mstr_standard
J 0
(-3700 3925);
DISPLAY 0.723404 (-3700 3925);
PAINT MONO (-3700 3925);
DISPLAY INVISIBLE (-3700 3925);
FORCEPROP 1 LAST BODY_TYPE PLUMBING
J 0
(-3700 3975);
DISPLAY 0.872340 (-3700 3975);
PAINT GREEN (-3700 3975);
DISPLAY INVISIBLE (-3700 3975);
FORCEPROP 1 LAST HDL_TAP TRUE
J 0
(-3375 3800);
DISPLAY 0.872340 (-3375 3800);
DISPLAY INVISIBLE (-3375 3800);
FORCEPROP 1 LAST PATH I391
J 0
(-3702 3925);
DISPLAY 0.872340 (-3702 3925);
PAINT GREEN (-3702 3925);
DISPLAY INVISIBLE (-3702 3925);
FORCEADD TAP..1
(-3700 3825);
FORCEPROP 3 LASTPIN (-3750 3825) SIG_NAME M_D_CPU0_SA_DQS_DP<1>
J 0
(-3740 3835);
DISPLAY 0.659574 (-3740 3835);
PAINT MONO (-3740 3835);
DISPLAY INVISIBLE (-3740 3835);
FORCEPROP 1 LASTPIN (-3750 3825) BN 1
J 0
(-3762 3833);
DISPLAY 0.489362 (-3762 3833);
PAINT GREEN (-3762 3833);
FORCEPROP 2 LAST CDS_LIB mstr_standard
J 0
(-3700 3825);
DISPLAY 0.723404 (-3700 3825);
PAINT MONO (-3700 3825);
DISPLAY INVISIBLE (-3700 3825);
FORCEPROP 1 LAST BODY_TYPE PLUMBING
J 0
(-3700 3875);
DISPLAY 0.872340 (-3700 3875);
PAINT GREEN (-3700 3875);
DISPLAY INVISIBLE (-3700 3875);
FORCEPROP 1 LAST HDL_TAP TRUE
J 0
(-3375 3700);
DISPLAY 0.872340 (-3375 3700);
DISPLAY INVISIBLE (-3375 3700);
FORCEPROP 1 LAST PATH I392
J 0
(-3702 3825);
DISPLAY 0.872340 (-3702 3825);
PAINT GREEN (-3702 3825);
DISPLAY INVISIBLE (-3702 3825);
FORCEADD TAP..1
(-3500 3675);
FORCEPROP 3 LASTPIN (-3550 3675) SIG_NAME M_D_CPU0_SA_DQS_DN<0>
J 0
(-3540 3685);
DISPLAY 0.659574 (-3540 3685);
PAINT MONO (-3540 3685);
DISPLAY INVISIBLE (-3540 3685);
FORCEPROP 1 LASTPIN (-3550 3675) BN 0
J 0
(-3562 3683);
DISPLAY 0.489362 (-3562 3683);
PAINT GREEN (-3562 3683);
FORCEPROP 2 LAST CDS_LIB mstr_standard
J 0
(-3500 3675);
DISPLAY 0.723404 (-3500 3675);
PAINT MONO (-3500 3675);
DISPLAY INVISIBLE (-3500 3675);
FORCEPROP 1 LAST BODY_TYPE PLUMBING
J 0
(-3500 3725);
DISPLAY 0.872340 (-3500 3725);
PAINT GREEN (-3500 3725);
DISPLAY INVISIBLE (-3500 3725);
FORCEPROP 1 LAST HDL_TAP TRUE
J 0
(-3175 3550);
DISPLAY 0.872340 (-3175 3550);
DISPLAY INVISIBLE (-3175 3550);
FORCEPROP 1 LAST PATH I393
J 0
(-3502 3675);
DISPLAY 0.872340 (-3502 3675);
PAINT GREEN (-3502 3675);
DISPLAY INVISIBLE (-3502 3675);
FORCEADD TAP..1
(-3500 3525);
FORCEPROP 3 LASTPIN (-3550 3525) SIG_NAME M_D_CPU0_SB_DQS_DN<9>
J 0
(-3540 3535);
DISPLAY 0.659574 (-3540 3535);
PAINT MONO (-3540 3535);
DISPLAY INVISIBLE (-3540 3535);
FORCEPROP 1 LASTPIN (-3550 3525) BN 9
J 0
(-3562 3533);
DISPLAY 0.489362 (-3562 3533);
PAINT GREEN (-3562 3533);
FORCEPROP 2 LAST CDS_LIB mstr_standard
J 0
(-3500 3525);
DISPLAY 0.723404 (-3500 3525);
PAINT MONO (-3500 3525);
DISPLAY INVISIBLE (-3500 3525);
FORCEPROP 1 LAST BODY_TYPE PLUMBING
J 0
(-3500 3575);
DISPLAY 0.872340 (-3500 3575);
PAINT GREEN (-3500 3575);
DISPLAY INVISIBLE (-3500 3575);
FORCEPROP 1 LAST HDL_TAP TRUE
J 0
(-3175 3400);
DISPLAY 0.872340 (-3175 3400);
DISPLAY INVISIBLE (-3175 3400);
FORCEPROP 1 LAST PATH I394
J 0
(-3502 3525);
DISPLAY 0.872340 (-3502 3525);
PAINT GREEN (-3502 3525);
DISPLAY INVISIBLE (-3502 3525);
FORCEADD TAP..1
(-3500 3425);
FORCEPROP 3 LASTPIN (-3550 3425) SIG_NAME M_D_CPU0_SB_DQS_DN<8>
J 0
(-3540 3435);
DISPLAY 0.659574 (-3540 3435);
PAINT MONO (-3540 3435);
DISPLAY INVISIBLE (-3540 3435);
FORCEPROP 1 LASTPIN (-3550 3425) BN 8
J 0
(-3562 3433);
DISPLAY 0.489362 (-3562 3433);
PAINT GREEN (-3562 3433);
FORCEPROP 2 LAST CDS_LIB mstr_standard
J 0
(-3500 3425);
DISPLAY 0.723404 (-3500 3425);
PAINT MONO (-3500 3425);
DISPLAY INVISIBLE (-3500 3425);
FORCEPROP 1 LAST BODY_TYPE PLUMBING
J 0
(-3500 3475);
DISPLAY 0.872340 (-3500 3475);
PAINT GREEN (-3500 3475);
DISPLAY INVISIBLE (-3500 3475);
FORCEPROP 1 LAST HDL_TAP TRUE
J 0
(-3175 3300);
DISPLAY 0.872340 (-3175 3300);
DISPLAY INVISIBLE (-3175 3300);
FORCEPROP 1 LAST PATH I395
J 0
(-3502 3425);
DISPLAY 0.872340 (-3502 3425);
PAINT GREEN (-3502 3425);
DISPLAY INVISIBLE (-3502 3425);
FORCEADD TAP..1
(-3500 3325);
FORCEPROP 3 LASTPIN (-3550 3325) SIG_NAME M_D_CPU0_SB_DQS_DN<7>
J 0
(-3540 3335);
DISPLAY 0.659574 (-3540 3335);
PAINT MONO (-3540 3335);
DISPLAY INVISIBLE (-3540 3335);
FORCEPROP 1 LASTPIN (-3550 3325) BN 7
J 0
(-3562 3333);
DISPLAY 0.489362 (-3562 3333);
PAINT GREEN (-3562 3333);
FORCEPROP 2 LAST CDS_LIB mstr_standard
J 0
(-3500 3325);
DISPLAY 0.723404 (-3500 3325);
PAINT MONO (-3500 3325);
DISPLAY INVISIBLE (-3500 3325);
FORCEPROP 1 LAST BODY_TYPE PLUMBING
J 0
(-3500 3375);
DISPLAY 0.872340 (-3500 3375);
PAINT GREEN (-3500 3375);
DISPLAY INVISIBLE (-3500 3375);
FORCEPROP 1 LAST HDL_TAP TRUE
J 0
(-3175 3200);
DISPLAY 0.872340 (-3175 3200);
DISPLAY INVISIBLE (-3175 3200);
FORCEPROP 1 LAST PATH I396
J 0
(-3502 3325);
DISPLAY 0.872340 (-3502 3325);
PAINT GREEN (-3502 3325);
DISPLAY INVISIBLE (-3502 3325);
FORCEADD TAP..1
(-3700 3575);
FORCEPROP 3 LASTPIN (-3750 3575) SIG_NAME M_D_CPU0_SB_DQS_DP<9>
J 0
(-3740 3585);
DISPLAY 0.659574 (-3740 3585);
PAINT MONO (-3740 3585);
DISPLAY INVISIBLE (-3740 3585);
FORCEPROP 1 LASTPIN (-3750 3575) BN 9
J 0
(-3762 3583);
DISPLAY 0.489362 (-3762 3583);
PAINT GREEN (-3762 3583);
FORCEPROP 2 LAST CDS_LIB mstr_standard
J 0
(-3700 3575);
DISPLAY 0.723404 (-3700 3575);
PAINT MONO (-3700 3575);
DISPLAY INVISIBLE (-3700 3575);
FORCEPROP 1 LAST BODY_TYPE PLUMBING
J 0
(-3700 3625);
DISPLAY 0.872340 (-3700 3625);
PAINT GREEN (-3700 3625);
DISPLAY INVISIBLE (-3700 3625);
FORCEPROP 1 LAST HDL_TAP TRUE
J 0
(-3375 3450);
DISPLAY 0.872340 (-3375 3450);
DISPLAY INVISIBLE (-3375 3450);
FORCEPROP 1 LAST PATH I397
J 0
(-3702 3575);
DISPLAY 0.872340 (-3702 3575);
PAINT GREEN (-3702 3575);
DISPLAY INVISIBLE (-3702 3575);
FORCEADD TAP..1
(-3700 3725);
FORCEPROP 3 LASTPIN (-3750 3725) SIG_NAME M_D_CPU0_SA_DQS_DP<0>
J 0
(-3740 3735);
DISPLAY 0.659574 (-3740 3735);
PAINT MONO (-3740 3735);
DISPLAY INVISIBLE (-3740 3735);
FORCEPROP 1 LASTPIN (-3750 3725) BN 0
J 0
(-3762 3733);
DISPLAY 0.489362 (-3762 3733);
PAINT GREEN (-3762 3733);
FORCEPROP 2 LAST CDS_LIB mstr_standard
J 0
(-3700 3725);
DISPLAY 0.723404 (-3700 3725);
PAINT MONO (-3700 3725);
DISPLAY INVISIBLE (-3700 3725);
FORCEPROP 1 LAST BODY_TYPE PLUMBING
J 0
(-3700 3775);
DISPLAY 0.872340 (-3700 3775);
PAINT GREEN (-3700 3775);
DISPLAY INVISIBLE (-3700 3775);
FORCEPROP 1 LAST HDL_TAP TRUE
J 0
(-3375 3600);
DISPLAY 0.872340 (-3375 3600);
DISPLAY INVISIBLE (-3375 3600);
FORCEPROP 1 LAST PATH I398
J 0
(-3702 3725);
DISPLAY 0.872340 (-3702 3725);
PAINT GREEN (-3702 3725);
DISPLAY INVISIBLE (-3702 3725);
FORCEADD TAP..1
(-3700 3375);
FORCEPROP 3 LASTPIN (-3750 3375) SIG_NAME M_D_CPU0_SB_DQS_DP<7>
J 0
(-3740 3385);
DISPLAY 0.659574 (-3740 3385);
PAINT MONO (-3740 3385);
DISPLAY INVISIBLE (-3740 3385);
FORCEPROP 1 LASTPIN (-3750 3375) BN 7
J 0
(-3762 3383);
DISPLAY 0.489362 (-3762 3383);
PAINT GREEN (-3762 3383);
FORCEPROP 2 LAST CDS_LIB mstr_standard
J 0
(-3700 3375);
DISPLAY 0.723404 (-3700 3375);
PAINT MONO (-3700 3375);
DISPLAY INVISIBLE (-3700 3375);
FORCEPROP 1 LAST BODY_TYPE PLUMBING
J 0
(-3700 3425);
DISPLAY 0.872340 (-3700 3425);
PAINT GREEN (-3700 3425);
DISPLAY INVISIBLE (-3700 3425);
FORCEPROP 1 LAST HDL_TAP TRUE
J 0
(-3375 3250);
DISPLAY 0.872340 (-3375 3250);
DISPLAY INVISIBLE (-3375 3250);
FORCEPROP 1 LAST PATH I399
J 0
(-3702 3375);
DISPLAY 0.872340 (-3702 3375);
PAINT GREEN (-3702 3375);
DISPLAY INVISIBLE (-3702 3375);
FORCEADD TAP..1
(-3700 3475);
FORCEPROP 3 LASTPIN (-3750 3475) SIG_NAME M_D_CPU0_SB_DQS_DP<8>
J 0
(-3740 3485);
DISPLAY 0.659574 (-3740 3485);
PAINT MONO (-3740 3485);
DISPLAY INVISIBLE (-3740 3485);
FORCEPROP 1 LASTPIN (-3750 3475) BN 8
J 0
(-3762 3483);
DISPLAY 0.489362 (-3762 3483);
PAINT GREEN (-3762 3483);
FORCEPROP 2 LAST CDS_LIB mstr_standard
J 0
(-3700 3475);
DISPLAY 0.723404 (-3700 3475);
PAINT MONO (-3700 3475);
DISPLAY INVISIBLE (-3700 3475);
FORCEPROP 1 LAST BODY_TYPE PLUMBING
J 0
(-3700 3525);
DISPLAY 0.872340 (-3700 3525);
PAINT GREEN (-3700 3525);
DISPLAY INVISIBLE (-3700 3525);
FORCEPROP 1 LAST HDL_TAP TRUE
J 0
(-3375 3350);
DISPLAY 0.872340 (-3375 3350);
DISPLAY INVISIBLE (-3375 3350);
FORCEPROP 1 LAST PATH I400
J 0
(-3702 3475);
DISPLAY 0.872340 (-3702 3475);
PAINT GREEN (-3702 3475);
DISPLAY INVISIBLE (-3702 3475);
FORCEADD TAP..1
(-3700 3275);
FORCEPROP 3 LASTPIN (-3750 3275) SIG_NAME M_D_CPU0_SB_DQS_DP<6>
J 0
(-3740 3285);
DISPLAY 0.659574 (-3740 3285);
PAINT MONO (-3740 3285);
DISPLAY INVISIBLE (-3740 3285);
FORCEPROP 1 LASTPIN (-3750 3275) BN 6
J 0
(-3762 3283);
DISPLAY 0.489362 (-3762 3283);
PAINT GREEN (-3762 3283);
FORCEPROP 2 LAST CDS_LIB mstr_standard
J 0
(-3700 3275);
DISPLAY 0.723404 (-3700 3275);
PAINT MONO (-3700 3275);
DISPLAY INVISIBLE (-3700 3275);
FORCEPROP 1 LAST BODY_TYPE PLUMBING
J 0
(-3700 3325);
DISPLAY 0.872340 (-3700 3325);
PAINT GREEN (-3700 3325);
DISPLAY INVISIBLE (-3700 3325);
FORCEPROP 1 LAST HDL_TAP TRUE
J 0
(-3375 3150);
DISPLAY 0.872340 (-3375 3150);
DISPLAY INVISIBLE (-3375 3150);
FORCEPROP 1 LAST PATH I401
J 0
(-3702 3275);
DISPLAY 0.872340 (-3702 3275);
PAINT GREEN (-3702 3275);
DISPLAY INVISIBLE (-3702 3275);
FORCEADD TAP..1
(-3500 3225);
FORCEPROP 3 LASTPIN (-3550 3225) SIG_NAME M_D_CPU0_SB_DQS_DN<6>
J 0
(-3540 3235);
DISPLAY 0.659574 (-3540 3235);
PAINT MONO (-3540 3235);
DISPLAY INVISIBLE (-3540 3235);
FORCEPROP 1 LASTPIN (-3550 3225) BN 6
J 0
(-3562 3233);
DISPLAY 0.489362 (-3562 3233);
PAINT GREEN (-3562 3233);
FORCEPROP 2 LAST CDS_LIB mstr_standard
J 0
(-3500 3225);
DISPLAY 0.723404 (-3500 3225);
PAINT MONO (-3500 3225);
DISPLAY INVISIBLE (-3500 3225);
FORCEPROP 1 LAST BODY_TYPE PLUMBING
J 0
(-3500 3275);
DISPLAY 0.872340 (-3500 3275);
PAINT GREEN (-3500 3275);
DISPLAY INVISIBLE (-3500 3275);
FORCEPROP 1 LAST HDL_TAP TRUE
J 0
(-3175 3100);
DISPLAY 0.872340 (-3175 3100);
DISPLAY INVISIBLE (-3175 3100);
FORCEPROP 1 LAST PATH I402
J 0
(-3502 3225);
DISPLAY 0.872340 (-3502 3225);
PAINT GREEN (-3502 3225);
DISPLAY INVISIBLE (-3502 3225);
FORCEADD TAP..1
(-3500 3125);
FORCEPROP 3 LASTPIN (-3550 3125) SIG_NAME M_D_CPU0_SB_DQS_DN<5>
J 0
(-3540 3135);
DISPLAY 0.659574 (-3540 3135);
PAINT MONO (-3540 3135);
DISPLAY INVISIBLE (-3540 3135);
FORCEPROP 1 LASTPIN (-3550 3125) BN 5
J 0
(-3562 3133);
DISPLAY 0.489362 (-3562 3133);
PAINT GREEN (-3562 3133);
FORCEPROP 2 LAST CDS_LIB mstr_standard
J 0
(-3500 3125);
DISPLAY 0.723404 (-3500 3125);
PAINT MONO (-3500 3125);
DISPLAY INVISIBLE (-3500 3125);
FORCEPROP 1 LAST BODY_TYPE PLUMBING
J 0
(-3500 3175);
DISPLAY 0.872340 (-3500 3175);
PAINT GREEN (-3500 3175);
DISPLAY INVISIBLE (-3500 3175);
FORCEPROP 1 LAST HDL_TAP TRUE
J 0
(-3175 3000);
DISPLAY 0.872340 (-3175 3000);
DISPLAY INVISIBLE (-3175 3000);
FORCEPROP 1 LAST PATH I403
J 0
(-3502 3125);
DISPLAY 0.872340 (-3502 3125);
PAINT GREEN (-3502 3125);
DISPLAY INVISIBLE (-3502 3125);
FORCEADD TAP..1
(-3500 3025);
FORCEPROP 3 LASTPIN (-3550 3025) SIG_NAME M_D_CPU0_SB_DQS_DN<4>
J 0
(-3540 3035);
DISPLAY 0.659574 (-3540 3035);
PAINT MONO (-3540 3035);
DISPLAY INVISIBLE (-3540 3035);
FORCEPROP 1 LASTPIN (-3550 3025) BN 4
J 0
(-3562 3033);
DISPLAY 0.489362 (-3562 3033);
PAINT GREEN (-3562 3033);
FORCEPROP 2 LAST CDS_LIB mstr_standard
J 0
(-3500 3025);
DISPLAY 0.723404 (-3500 3025);
PAINT MONO (-3500 3025);
DISPLAY INVISIBLE (-3500 3025);
FORCEPROP 1 LAST BODY_TYPE PLUMBING
J 0
(-3500 3075);
DISPLAY 0.872340 (-3500 3075);
PAINT GREEN (-3500 3075);
DISPLAY INVISIBLE (-3500 3075);
FORCEPROP 1 LAST HDL_TAP TRUE
J 0
(-3175 2900);
DISPLAY 0.872340 (-3175 2900);
DISPLAY INVISIBLE (-3175 2900);
FORCEPROP 1 LAST PATH I404
J 0
(-3502 3025);
DISPLAY 0.872340 (-3502 3025);
PAINT GREEN (-3502 3025);
DISPLAY INVISIBLE (-3502 3025);
FORCEADD TAP..1
(-3500 2925);
FORCEPROP 3 LASTPIN (-3550 2925) SIG_NAME M_D_CPU0_SB_DQS_DN<3>
J 0
(-3540 2935);
DISPLAY 0.659574 (-3540 2935);
PAINT MONO (-3540 2935);
DISPLAY INVISIBLE (-3540 2935);
FORCEPROP 1 LASTPIN (-3550 2925) BN 3
J 0
(-3562 2933);
DISPLAY 0.489362 (-3562 2933);
PAINT GREEN (-3562 2933);
FORCEPROP 2 LAST CDS_LIB mstr_standard
J 0
(-3500 2925);
DISPLAY 0.723404 (-3500 2925);
PAINT MONO (-3500 2925);
DISPLAY INVISIBLE (-3500 2925);
FORCEPROP 1 LAST BODY_TYPE PLUMBING
J 0
(-3500 2975);
DISPLAY 0.872340 (-3500 2975);
PAINT GREEN (-3500 2975);
DISPLAY INVISIBLE (-3500 2975);
FORCEPROP 1 LAST HDL_TAP TRUE
J 0
(-3175 2800);
DISPLAY 0.872340 (-3175 2800);
DISPLAY INVISIBLE (-3175 2800);
FORCEPROP 1 LAST PATH I405
J 0
(-3502 2925);
DISPLAY 0.872340 (-3502 2925);
PAINT GREEN (-3502 2925);
DISPLAY INVISIBLE (-3502 2925);
FORCEADD TAP..1
(-3500 2825);
FORCEPROP 3 LASTPIN (-3550 2825) SIG_NAME M_D_CPU0_SB_DQS_DN<2>
J 0
(-3540 2835);
DISPLAY 0.659574 (-3540 2835);
PAINT MONO (-3540 2835);
DISPLAY INVISIBLE (-3540 2835);
FORCEPROP 1 LASTPIN (-3550 2825) BN 2
J 0
(-3562 2833);
DISPLAY 0.489362 (-3562 2833);
PAINT GREEN (-3562 2833);
FORCEPROP 2 LAST CDS_LIB mstr_standard
J 0
(-3500 2825);
DISPLAY 0.723404 (-3500 2825);
PAINT MONO (-3500 2825);
DISPLAY INVISIBLE (-3500 2825);
FORCEPROP 1 LAST BODY_TYPE PLUMBING
J 0
(-3500 2875);
DISPLAY 0.872340 (-3500 2875);
PAINT GREEN (-3500 2875);
DISPLAY INVISIBLE (-3500 2875);
FORCEPROP 1 LAST HDL_TAP TRUE
J 0
(-3175 2700);
DISPLAY 0.872340 (-3175 2700);
DISPLAY INVISIBLE (-3175 2700);
FORCEPROP 1 LAST PATH I406
J 0
(-3502 2825);
DISPLAY 0.872340 (-3502 2825);
PAINT GREEN (-3502 2825);
DISPLAY INVISIBLE (-3502 2825);
FORCEADD TAP..1
(-3500 2725);
FORCEPROP 3 LASTPIN (-3550 2725) SIG_NAME M_D_CPU0_SB_DQS_DN<1>
J 0
(-3540 2735);
DISPLAY 0.659574 (-3540 2735);
PAINT MONO (-3540 2735);
DISPLAY INVISIBLE (-3540 2735);
FORCEPROP 1 LASTPIN (-3550 2725) BN 1
J 0
(-3562 2733);
DISPLAY 0.489362 (-3562 2733);
PAINT GREEN (-3562 2733);
FORCEPROP 2 LAST CDS_LIB mstr_standard
J 0
(-3500 2725);
DISPLAY 0.723404 (-3500 2725);
PAINT MONO (-3500 2725);
DISPLAY INVISIBLE (-3500 2725);
FORCEPROP 1 LAST BODY_TYPE PLUMBING
J 0
(-3500 2775);
DISPLAY 0.872340 (-3500 2775);
PAINT GREEN (-3500 2775);
DISPLAY INVISIBLE (-3500 2775);
FORCEPROP 1 LAST HDL_TAP TRUE
J 0
(-3175 2600);
DISPLAY 0.872340 (-3175 2600);
DISPLAY INVISIBLE (-3175 2600);
FORCEPROP 1 LAST PATH I407
J 0
(-3502 2725);
DISPLAY 0.872340 (-3502 2725);
PAINT GREEN (-3502 2725);
DISPLAY INVISIBLE (-3502 2725);
FORCEADD TAP..1
(-3700 3175);
FORCEPROP 3 LASTPIN (-3750 3175) SIG_NAME M_D_CPU0_SB_DQS_DP<5>
J 0
(-3740 3185);
DISPLAY 0.659574 (-3740 3185);
PAINT MONO (-3740 3185);
DISPLAY INVISIBLE (-3740 3185);
FORCEPROP 1 LASTPIN (-3750 3175) BN 5
J 0
(-3762 3183);
DISPLAY 0.489362 (-3762 3183);
PAINT GREEN (-3762 3183);
FORCEPROP 2 LAST CDS_LIB mstr_standard
J 0
(-3700 3175);
DISPLAY 0.723404 (-3700 3175);
PAINT MONO (-3700 3175);
DISPLAY INVISIBLE (-3700 3175);
FORCEPROP 1 LAST BODY_TYPE PLUMBING
J 0
(-3700 3225);
DISPLAY 0.872340 (-3700 3225);
PAINT GREEN (-3700 3225);
DISPLAY INVISIBLE (-3700 3225);
FORCEPROP 1 LAST HDL_TAP TRUE
J 0
(-3375 3050);
DISPLAY 0.872340 (-3375 3050);
DISPLAY INVISIBLE (-3375 3050);
FORCEPROP 1 LAST PATH I408
J 0
(-3702 3175);
DISPLAY 0.872340 (-3702 3175);
PAINT GREEN (-3702 3175);
DISPLAY INVISIBLE (-3702 3175);
FORCEADD TAP..1
(-3700 3075);
FORCEPROP 3 LASTPIN (-3750 3075) SIG_NAME M_D_CPU0_SB_DQS_DP<4>
J 0
(-3740 3085);
DISPLAY 0.659574 (-3740 3085);
PAINT MONO (-3740 3085);
DISPLAY INVISIBLE (-3740 3085);
FORCEPROP 1 LASTPIN (-3750 3075) BN 4
J 0
(-3762 3083);
DISPLAY 0.489362 (-3762 3083);
PAINT GREEN (-3762 3083);
FORCEPROP 2 LAST CDS_LIB mstr_standard
J 0
(-3700 3075);
DISPLAY 0.723404 (-3700 3075);
PAINT MONO (-3700 3075);
DISPLAY INVISIBLE (-3700 3075);
FORCEPROP 1 LAST BODY_TYPE PLUMBING
J 0
(-3700 3125);
DISPLAY 0.872340 (-3700 3125);
PAINT GREEN (-3700 3125);
DISPLAY INVISIBLE (-3700 3125);
FORCEPROP 1 LAST HDL_TAP TRUE
J 0
(-3375 2950);
DISPLAY 0.872340 (-3375 2950);
DISPLAY INVISIBLE (-3375 2950);
FORCEPROP 1 LAST PATH I409
J 0
(-3702 3075);
DISPLAY 0.872340 (-3702 3075);
PAINT GREEN (-3702 3075);
DISPLAY INVISIBLE (-3702 3075);
FORCEADD TAP..1
(-3700 2875);
FORCEPROP 3 LASTPIN (-3750 2875) SIG_NAME M_D_CPU0_SB_DQS_DP<2>
J 0
(-3740 2885);
DISPLAY 0.659574 (-3740 2885);
PAINT MONO (-3740 2885);
DISPLAY INVISIBLE (-3740 2885);
FORCEPROP 1 LASTPIN (-3750 2875) BN 2
J 0
(-3762 2883);
DISPLAY 0.489362 (-3762 2883);
PAINT GREEN (-3762 2883);
FORCEPROP 2 LAST CDS_LIB mstr_standard
J 0
(-3700 2875);
DISPLAY 0.723404 (-3700 2875);
PAINT MONO (-3700 2875);
DISPLAY INVISIBLE (-3700 2875);
FORCEPROP 1 LAST BODY_TYPE PLUMBING
J 0
(-3700 2925);
DISPLAY 0.872340 (-3700 2925);
PAINT GREEN (-3700 2925);
DISPLAY INVISIBLE (-3700 2925);
FORCEPROP 1 LAST HDL_TAP TRUE
J 0
(-3375 2750);
DISPLAY 0.872340 (-3375 2750);
DISPLAY INVISIBLE (-3375 2750);
FORCEPROP 1 LAST PATH I410
J 0
(-3702 2875);
DISPLAY 0.872340 (-3702 2875);
PAINT GREEN (-3702 2875);
DISPLAY INVISIBLE (-3702 2875);
FORCEADD TAP..1
(-3700 2975);
FORCEPROP 3 LASTPIN (-3750 2975) SIG_NAME M_D_CPU0_SB_DQS_DP<3>
J 0
(-3740 2985);
DISPLAY 0.659574 (-3740 2985);
PAINT MONO (-3740 2985);
DISPLAY INVISIBLE (-3740 2985);
FORCEPROP 1 LASTPIN (-3750 2975) BN 3
J 0
(-3762 2983);
DISPLAY 0.489362 (-3762 2983);
PAINT GREEN (-3762 2983);
FORCEPROP 2 LAST CDS_LIB mstr_standard
J 0
(-3700 2975);
DISPLAY 0.723404 (-3700 2975);
PAINT MONO (-3700 2975);
DISPLAY INVISIBLE (-3700 2975);
FORCEPROP 1 LAST BODY_TYPE PLUMBING
J 0
(-3700 3025);
DISPLAY 0.872340 (-3700 3025);
PAINT GREEN (-3700 3025);
DISPLAY INVISIBLE (-3700 3025);
FORCEPROP 1 LAST HDL_TAP TRUE
J 0
(-3375 2850);
DISPLAY 0.872340 (-3375 2850);
DISPLAY INVISIBLE (-3375 2850);
FORCEPROP 1 LAST PATH I411
J 0
(-3702 2975);
DISPLAY 0.872340 (-3702 2975);
PAINT GREEN (-3702 2975);
DISPLAY INVISIBLE (-3702 2975);
FORCEADD TAP..1
(-3700 2775);
FORCEPROP 3 LASTPIN (-3750 2775) SIG_NAME M_D_CPU0_SB_DQS_DP<1>
J 0
(-3740 2785);
DISPLAY 0.659574 (-3740 2785);
PAINT MONO (-3740 2785);
DISPLAY INVISIBLE (-3740 2785);
FORCEPROP 1 LASTPIN (-3750 2775) BN 1
J 0
(-3762 2783);
DISPLAY 0.489362 (-3762 2783);
PAINT GREEN (-3762 2783);
FORCEPROP 2 LAST CDS_LIB mstr_standard
J 0
(-3700 2775);
DISPLAY 0.723404 (-3700 2775);
PAINT MONO (-3700 2775);
DISPLAY INVISIBLE (-3700 2775);
FORCEPROP 1 LAST BODY_TYPE PLUMBING
J 0
(-3700 2825);
DISPLAY 0.872340 (-3700 2825);
PAINT GREEN (-3700 2825);
DISPLAY INVISIBLE (-3700 2825);
FORCEPROP 1 LAST HDL_TAP TRUE
J 0
(-3375 2650);
DISPLAY 0.872340 (-3375 2650);
DISPLAY INVISIBLE (-3375 2650);
FORCEPROP 1 LAST PATH I412
J 0
(-3702 2775);
DISPLAY 0.872340 (-3702 2775);
PAINT GREEN (-3702 2775);
DISPLAY INVISIBLE (-3702 2775);
FORCEADD TAP..1
(-3500 2625);
FORCEPROP 3 LASTPIN (-3550 2625) SIG_NAME M_D_CPU0_SB_DQS_DN<0>
J 0
(-3540 2635);
DISPLAY 0.659574 (-3540 2635);
PAINT MONO (-3540 2635);
DISPLAY INVISIBLE (-3540 2635);
FORCEPROP 1 LASTPIN (-3550 2625) BN 0
J 0
(-3562 2633);
DISPLAY 0.489362 (-3562 2633);
PAINT GREEN (-3562 2633);
FORCEPROP 2 LAST CDS_LIB mstr_standard
J 0
(-3500 2625);
DISPLAY 0.723404 (-3500 2625);
PAINT MONO (-3500 2625);
DISPLAY INVISIBLE (-3500 2625);
FORCEPROP 1 LAST BODY_TYPE PLUMBING
J 0
(-3500 2675);
DISPLAY 0.872340 (-3500 2675);
PAINT GREEN (-3500 2675);
DISPLAY INVISIBLE (-3500 2675);
FORCEPROP 1 LAST HDL_TAP TRUE
J 0
(-3175 2500);
DISPLAY 0.872340 (-3175 2500);
DISPLAY INVISIBLE (-3175 2500);
FORCEPROP 1 LAST PATH I413
J 0
(-3502 2625);
DISPLAY 0.872340 (-3502 2625);
PAINT GREEN (-3502 2625);
DISPLAY INVISIBLE (-3502 2625);
FORCEADD TAP..1
(-3700 2675);
FORCEPROP 3 LASTPIN (-3750 2675) SIG_NAME M_D_CPU0_SB_DQS_DP<0>
J 0
(-3740 2685);
DISPLAY 0.659574 (-3740 2685);
PAINT MONO (-3740 2685);
DISPLAY INVISIBLE (-3740 2685);
FORCEPROP 1 LASTPIN (-3750 2675) BN 0
J 0
(-3762 2683);
DISPLAY 0.489362 (-3762 2683);
PAINT GREEN (-3762 2683);
FORCEPROP 2 LAST CDS_LIB mstr_standard
J 0
(-3700 2675);
DISPLAY 0.723404 (-3700 2675);
PAINT MONO (-3700 2675);
DISPLAY INVISIBLE (-3700 2675);
FORCEPROP 1 LAST BODY_TYPE PLUMBING
J 0
(-3700 2725);
DISPLAY 0.872340 (-3700 2725);
PAINT GREEN (-3700 2725);
DISPLAY INVISIBLE (-3700 2725);
FORCEPROP 1 LAST HDL_TAP TRUE
J 0
(-3375 2550);
DISPLAY 0.872340 (-3375 2550);
DISPLAY INVISIBLE (-3375 2550);
FORCEPROP 1 LAST PATH I414
J 0
(-3702 2675);
DISPLAY 0.872340 (-3702 2675);
PAINT GREEN (-3702 2675);
DISPLAY INVISIBLE (-3702 2675);
FORCEADD SCONN288_DDR506112002KQ..2
(-4650 3625);
FORCEPROP 1 LAST LOCATION J19
J 0
(-5250 4950);
DISPLAY 0.468085 (-5250 4950);
PAINT SKYBLUE (-5250 4950);
FORCEPROP 0 LAST $SEC 2
J 0
(-5100 5100);
DISPLAY 0.680851 (-5100 5100);
PAINT MONO (-5100 5100);
DISPLAY INVISIBLE (-5100 5100);
FORCEPROP 0 LAST CDS_SEC 2
J 0
(-5100 5100);
DISPLAY 1.021277 (-5100 5100);
DISPLAY INVISIBLE (-5100 5100);
FORCEPROP 0 LASTPIN (-3900 3675) $PN 12
J 0
(-3890 3685);
DISPLAY 0.680851 (-3890 3685);
PAINT MONO (-3890 3685);
FORCEPROP 0 LASTPIN (-3900 3725) $PN 11
J 0
(-3890 3735);
DISPLAY 0.680851 (-3890 3735);
PAINT MONO (-3890 3735);
FORCEPROP 0 LASTPIN (-3900 2625) $PN 105
J 0
(-3890 2635);
DISPLAY 0.680851 (-3890 2635);
PAINT MONO (-3890 2635);
FORCEPROP 0 LASTPIN (-3900 2675) $PN 104
J 0
(-3890 2685);
DISPLAY 0.680851 (-3890 2685);
PAINT MONO (-3890 2685);
FORCEPROP 0 LASTPIN (-3900 3775) $PN 23
J 0
(-3890 3785);
DISPLAY 0.680851 (-3890 3785);
PAINT MONO (-3890 3785);
FORCEPROP 0 LASTPIN (-3900 3825) $PN 22
J 0
(-3890 3835);
DISPLAY 0.680851 (-3890 3835);
PAINT MONO (-3890 3835);
FORCEPROP 0 LASTPIN (-3900 2725) $PN 116
J 0
(-3890 2735);
DISPLAY 0.680851 (-3890 2735);
PAINT MONO (-3890 2735);
FORCEPROP 0 LASTPIN (-3900 2775) $PN 115
J 0
(-3890 2785);
DISPLAY 0.680851 (-3890 2785);
PAINT MONO (-3890 2785);
FORCEPROP 0 LASTPIN (-3900 3875) $PN 34
J 0
(-3890 3885);
DISPLAY 0.680851 (-3890 3885);
PAINT MONO (-3890 3885);
FORCEPROP 0 LASTPIN (-3900 3925) $PN 33
J 0
(-3890 3935);
DISPLAY 0.680851 (-3890 3935);
PAINT MONO (-3890 3935);
FORCEPROP 0 LASTPIN (-3900 2825) $PN 127
J 0
(-3890 2835);
DISPLAY 0.680851 (-3890 2835);
PAINT MONO (-3890 2835);
FORCEPROP 0 LASTPIN (-3900 2875) $PN 126
J 0
(-3890 2885);
DISPLAY 0.680851 (-3890 2885);
PAINT MONO (-3890 2885);
FORCEPROP 0 LASTPIN (-3900 3975) $PN 45
J 0
(-3890 3985);
DISPLAY 0.680851 (-3890 3985);
PAINT MONO (-3890 3985);
FORCEPROP 0 LASTPIN (-3900 4025) $PN 44
J 0
(-3890 4035);
DISPLAY 0.680851 (-3890 4035);
PAINT MONO (-3890 4035);
FORCEPROP 0 LASTPIN (-3900 2925) $PN 138
J 0
(-3890 2935);
DISPLAY 0.680851 (-3890 2935);
PAINT MONO (-3890 2935);
FORCEPROP 0 LASTPIN (-3900 2975) $PN 137
J 0
(-3890 2985);
DISPLAY 0.680851 (-3890 2985);
PAINT MONO (-3890 2985);
FORCEPROP 0 LASTPIN (-3900 4075) $PN 56
J 0
(-3890 4085);
DISPLAY 0.680851 (-3890 4085);
PAINT MONO (-3890 4085);
FORCEPROP 0 LASTPIN (-3900 4125) $PN 55
J 0
(-3890 4135);
DISPLAY 0.680851 (-3890 4135);
PAINT MONO (-3890 4135);
FORCEPROP 0 LASTPIN (-3900 3025) $PN 238
J 0
(-3890 3035);
DISPLAY 0.680851 (-3890 3035);
PAINT MONO (-3890 3035);
FORCEPROP 0 LASTPIN (-3900 3075) $PN 239
J 0
(-3890 3085);
DISPLAY 0.680851 (-3890 3085);
PAINT MONO (-3890 3085);
FORCEPROP 0 LASTPIN (-3900 4175) $PN 156
J 0
(-3890 4185);
DISPLAY 0.680851 (-3890 4185);
PAINT MONO (-3890 4185);
FORCEPROP 0 LASTPIN (-3900 4225) $PN 157
J 0
(-3890 4235);
DISPLAY 0.680851 (-3890 4235);
PAINT MONO (-3890 4235);
FORCEPROP 0 LASTPIN (-3900 3125) $PN 249
J 0
(-3890 3135);
DISPLAY 0.680851 (-3890 3135);
PAINT MONO (-3890 3135);
FORCEPROP 0 LASTPIN (-3900 3175) $PN 250
J 0
(-3890 3185);
DISPLAY 0.680851 (-3890 3185);
PAINT MONO (-3890 3185);
FORCEPROP 0 LASTPIN (-3900 4275) $PN 167
J 0
(-3890 4285);
DISPLAY 0.680851 (-3890 4285);
PAINT MONO (-3890 4285);
FORCEPROP 0 LASTPIN (-3900 4325) $PN 168
J 0
(-3890 4335);
DISPLAY 0.680851 (-3890 4335);
PAINT MONO (-3890 4335);
FORCEPROP 0 LASTPIN (-3900 3225) $PN 260
J 0
(-3890 3235);
DISPLAY 0.680851 (-3890 3235);
PAINT MONO (-3890 3235);
FORCEPROP 0 LASTPIN (-3900 3275) $PN 261
J 0
(-3890 3285);
DISPLAY 0.680851 (-3890 3285);
PAINT MONO (-3890 3285);
FORCEPROP 0 LASTPIN (-3900 4375) $PN 178
J 0
(-3890 4385);
DISPLAY 0.680851 (-3890 4385);
PAINT MONO (-3890 4385);
FORCEPROP 0 LASTPIN (-3900 4425) $PN 179
J 0
(-3890 4435);
DISPLAY 0.680851 (-3890 4435);
PAINT MONO (-3890 4435);
FORCEPROP 0 LASTPIN (-3900 3325) $PN 271
J 0
(-3890 3335);
DISPLAY 0.680851 (-3890 3335);
PAINT MONO (-3890 3335);
FORCEPROP 0 LASTPIN (-3900 3375) $PN 272
J 0
(-3890 3385);
DISPLAY 0.680851 (-3890 3385);
PAINT MONO (-3890 3385);
FORCEPROP 0 LASTPIN (-3900 4475) $PN 189
J 0
(-3890 4485);
DISPLAY 0.680851 (-3890 4485);
PAINT MONO (-3890 4485);
FORCEPROP 0 LASTPIN (-3900 4525) $PN 190
J 0
(-3890 4535);
DISPLAY 0.680851 (-3890 4535);
PAINT MONO (-3890 4535);
FORCEPROP 0 LASTPIN (-3900 3425) $PN 282
J 0
(-3890 3435);
DISPLAY 0.680851 (-3890 3435);
PAINT MONO (-3890 3435);
FORCEPROP 0 LASTPIN (-3900 3475) $PN 283
J 0
(-3890 3485);
DISPLAY 0.680851 (-3890 3485);
PAINT MONO (-3890 3485);
FORCEPROP 0 LASTPIN (-3900 4575) $PN 200
J 0
(-3890 4585);
DISPLAY 0.680851 (-3890 4585);
PAINT MONO (-3890 4585);
FORCEPROP 0 LASTPIN (-3900 4625) $PN 201
J 0
(-3890 4635);
DISPLAY 0.680851 (-3890 4635);
PAINT MONO (-3890 4635);
FORCEPROP 0 LASTPIN (-3900 3525) $PN 94
J 0
(-3890 3535);
DISPLAY 0.680851 (-3890 3535);
PAINT MONO (-3890 3535);
FORCEPROP 0 LASTPIN (-3900 3575) $PN 93
J 0
(-3890 3585);
DISPLAY 0.680851 (-3890 3585);
PAINT MONO (-3890 3585);
FORCEPROP 2 LAST VALUE SCONN288_DDR506112002KQ
J 0
(-5100 5000);
DISPLAY 0.489362 (-5100 5000);
PAINT SKYBLUE (-5100 5000);
FORCEPROP 2 LAST PART_TYPE SMLF
J 0
(-5100 5050);
DISPLAY 1.021277 (-5100 5050);
FORCEPROP 1 LAST MATERIAL IO
J 0
(-5250 4800);
DISPLAY 0.468085 (-5250 4800);
PAINT SKYBLUE (-5250 4800);
FORCEPROP 1 LAST CDS_LMAN_SYM_OUTLINE -600,1150,600,-1150
J 0
(-4650 3625);
DISPLAY 0.468085 (-4650 3625);
PAINT GREEN (-4650 3625);
DISPLAY INVISIBLE (-4650 3625);
FORCEPROP 1 LAST NEEDS_NO_SIZE TRUE
J 0
(-4650 3625);
DISPLAY 0.723404 (-4650 3625);
PAINT GREEN (-4650 3625);
DISPLAY INVISIBLE (-4650 3625);
FORCEPROP 2 LAST CDS_LIB pure_quanta
J 0
(-4650 3625);
DISPLAY INVISIBLE (-4650 3625);
FORCEPROP 1 LAST PATH I415
J 0
(-4650 3625);
DISPLAY 0.723404 (-4650 3625);
PAINT GREEN (-4650 3625);
DISPLAY INVISIBLE (-4650 3625);
FORCEPROP 1 LAST PART_NUMBER DFHST8FS479
J 0
(-5250 4875);
DISPLAY 0.468085 (-5250 4875);
PAINT SKYBLUE (-5250 4875);
DISPLAY INVISIBLE (-5250 4875);
FORCEADD GND..1
(-2950 5225);
FORCEPROP 3 LASTPIN (-2950 5275) SIG_NAME GND\g
J 0
(-2940 5285);
DISPLAY 0.659574 (-2940 5285);
PAINT MONO (-2940 5285);
DISPLAY INVISIBLE (-2940 5285);
FORCEPROP 2 LAST CDS_LIB pure_quanta_power
J 0
(-2950 5225);
DISPLAY INVISIBLE (-2950 5225);
FORCEPROP 2 LAST BOM_COST MEM
J 0
(-2925 5350);
DISPLAY 0.659574 (-2925 5350);
DISPLAY INVISIBLE (-2925 5350);
FORCEPROP 1 LAST SIZE 1B
J 0
(-2875 5175);
DISPLAY 0.723404 (-2875 5175);
PAINT GREEN (-2875 5175);
DISPLAY INVISIBLE (-2875 5175);
FORCEPROP 2 LAST ROOM MEM_EFGH_DECOUPLING_CAPS
J 0
(-2925 5300);
DISPLAY 0.659574 (-2925 5300);
PAINT RED (-2925 5300);
DISPLAY INVISIBLE (-2925 5300);
FORCEPROP 1 LAST HDL_POWER GND
J 0
(-2950 5375);
DISPLAY 0.723404 (-2950 5375);
PAINT GREEN (-2950 5375);
DISPLAY INVISIBLE (-2950 5375);
FORCEPROP 1 LAST PATH I416
J 0
(-2875 5225);
DISPLAY 0.872340 (-2875 5225);
PAINT AQUA (-2875 5225);
DISPLAY INVISIBLE (-2875 5225);
FORCEADD Q_CAP..1
R 2
(-2950 5575);
FORCEPROP 1 LAST LOCATION C149
J 2
(-3000 5675);
DISPLAY 0.489362 (-3000 5675);
PAINT SKYBLUE (-3000 5675);
FORCEPROP 0 LAST $SEC 1
J 0
(-3000 5725);
DISPLAY 0.680851 (-3000 5725);
PAINT MONO (-3000 5725);
DISPLAY INVISIBLE (-3000 5725);
FORCEPROP 0 LAST CDS_SEC 1
J 0
(-3000 5725);
DISPLAY 0.680851 (-3000 5725);
DISPLAY INVISIBLE (-3000 5725);
FORCEPROP 1 LASTPIN (-2950 5675) $PN 1
J 2
(-2960 5655);
DISPLAY 0.489362 (-2960 5655);
PAINT MONO (-2960 5655);
FORCEPROP 1 LASTPIN (-2950 5475) $PN 2
J 2
(-2960 5455);
DISPLAY 0.489362 (-2960 5455);
PAINT MONO (-2960 5455);
FORCEPROP 1 LAST TOLERANCE 10%
J 2
(-3000 5525);
DISPLAY 0.489362 (-3000 5525);
PAINT SKYBLUE (-3000 5525);
FORCEPROP 1 LAST MATERIAL X6S
J 2
(-3000 5475);
DISPLAY 0.489362 (-3000 5475);
PAINT SKYBLUE (-3000 5475);
FORCEPROP 1 LAST PACK_TYPE C0805
J 2
(-3000 5375);
DISPLAY 0.489362 (-3000 5375);
PAINT SKYBLUE (-3000 5375);
FORCEPROP 1 LAST VOLTAGE 25V
J 2
(-3000 5575);
DISPLAY 0.489362 (-3000 5575);
PAINT SKYBLUE (-3000 5575);
FORCEPROP 1 LAST VALUE 10UF
J 2
(-3000 5625);
DISPLAY 0.489362 (-3000 5625);
PAINT SKYBLUE (-3000 5625);
FORCEPROP 2 LAST CDS_LIB pure_quanta
J 0
(-2950 5575);
DISPLAY INVISIBLE (-2950 5575);
FORCEPROP 0 LAST BOM_COST MEM
J 2
(-3005 5720);
DISPLAY 0.595745 (-3005 5720);
PAINT MONO (-3005 5720);
DISPLAY INVISIBLE (-3005 5720);
FORCEPROP 2 LAST ROOM 
J 2
(-3005 5720);
DISPLAY 0.595745 (-3005 5720);
PAINT RED (-3005 5720);
DISPLAY INVISIBLE (-3005 5720);
FORCEPROP 1 LAST PATH I417
J 2
(-3000 5725);
DISPLAY 0.978723 (-3000 5725);
PAINT WHITE (-3000 5725);
DISPLAY INVISIBLE (-3000 5725);
FORCEPROP 1 LAST PART_NUMBER CH6104KEA00
J 2
(-3000 5425);
DISPLAY 0.489362 (-3000 5425);
PAINT SKYBLUE (-3000 5425);
DISPLAY INVISIBLE (-3000 5425);
FORCEADD Q_CAP..1
R 2
(-2375 5575);
FORCEPROP 1 LAST LOCATION C150
J 2
(-2425 5675);
DISPLAY 0.489362 (-2425 5675);
PAINT SKYBLUE (-2425 5675);
FORCEPROP 0 LAST $SEC 1
J 0
(-2425 5725);
DISPLAY 0.680851 (-2425 5725);
PAINT MONO (-2425 5725);
DISPLAY INVISIBLE (-2425 5725);
FORCEPROP 0 LAST CDS_SEC 1
J 0
(-2425 5725);
DISPLAY 0.680851 (-2425 5725);
DISPLAY INVISIBLE (-2425 5725);
FORCEPROP 1 LASTPIN (-2375 5675) $PN 1
J 2
(-2385 5655);
DISPLAY 0.489362 (-2385 5655);
PAINT MONO (-2385 5655);
FORCEPROP 1 LASTPIN (-2375 5475) $PN 2
J 2
(-2385 5455);
DISPLAY 0.489362 (-2385 5455);
PAINT MONO (-2385 5455);
FORCEPROP 1 LAST TOLERANCE 10%
J 2
(-2425 5525);
DISPLAY 0.489362 (-2425 5525);
PAINT SKYBLUE (-2425 5525);
FORCEPROP 1 LAST PACK_TYPE C0805
J 2
(-2425 5375);
DISPLAY 0.489362 (-2425 5375);
PAINT SKYBLUE (-2425 5375);
FORCEPROP 1 LAST VOLTAGE 25V
J 2
(-2425 5575);
DISPLAY 0.489362 (-2425 5575);
PAINT SKYBLUE (-2425 5575);
FORCEPROP 1 LAST VALUE 10UF
J 2
(-2425 5625);
DISPLAY 0.489362 (-2425 5625);
PAINT SKYBLUE (-2425 5625);
FORCEPROP 1 LAST MATERIAL X6S
J 2
(-2425 5475);
DISPLAY 0.489362 (-2425 5475);
PAINT SKYBLUE (-2425 5475);
FORCEPROP 2 LAST CDS_LIB pure_quanta
J 0
(-2375 5575);
DISPLAY INVISIBLE (-2375 5575);
FORCEPROP 0 LAST BOM_COST MEM
J 2
(-2430 5720);
DISPLAY 0.595745 (-2430 5720);
PAINT MONO (-2430 5720);
DISPLAY INVISIBLE (-2430 5720);
FORCEPROP 2 LAST ROOM 
J 2
(-2430 5720);
DISPLAY 0.595745 (-2430 5720);
PAINT RED (-2430 5720);
DISPLAY INVISIBLE (-2430 5720);
FORCEPROP 1 LAST PATH I418
J 2
(-2425 5725);
DISPLAY 0.978723 (-2425 5725);
PAINT WHITE (-2425 5725);
DISPLAY INVISIBLE (-2425 5725);
FORCEPROP 1 LAST PART_NUMBER CH6104KEA00
J 2
(-2425 5425);
DISPLAY 0.489362 (-2425 5425);
PAINT SKYBLUE (-2425 5425);
DISPLAY INVISIBLE (-2425 5425);
FORCEADD UNIVERSAL_POWER..1
(-2950 5900);
FORCEPROP 3 LASTPIN (-2950 5850) SIG_NAME P12V_MEM_CPU0\g
J 0
(-2940 5860);
DISPLAY 0.659574 (-2940 5860);
PAINT MONO (-2940 5860);
DISPLAY INVISIBLE (-2940 5860);
FORCEPROP 1 LAST HDL_POWER P12V_MEM_CPU0
J 1
(-2975 5950);
DISPLAY 0.489362 (-2975 5950);
PAINT GREEN (-2975 5950);
FORCEPROP 2 LAST BOM_COST VR_SYSTEM
J 0
(-2950 6000);
DISPLAY 0.617021 (-2950 6000);
PAINT PURPLE (-2950 6000);
DISPLAY INVISIBLE (-2950 6000);
FORCEPROP 2 LAST CDS_LIB pure_quanta_power
J 0
(-2950 5900);
DISPLAY INVISIBLE (-2950 5900);
FORCEPROP 1 LAST PATH I419
J 0
(-2900 5925);
DISPLAY 0.872340 (-2900 5925);
PAINT AQUA (-2900 5925);
DISPLAY INVISIBLE (-2900 5925);
FORCEADD OFFPAGE..1
(-8475 2775);
FORCEPROP 2 LAST $XR5 91 
J 0
(-9207 2775);
DISPLAY 0.638298 (-9207 2775);
PAINT MONO (-9207 2775);
FORCEPROP 2 LAST $XR4 90 
J 0
(-9117 2775);
DISPLAY 0.638298 (-9117 2775);
PAINT MONO (-9117 2775);
FORCEPROP 2 LAST $XR3 88 
J 0
(-9027 2775);
DISPLAY 0.638298 (-9027 2775);
PAINT MONO (-9027 2775);
FORCEPROP 2 LAST $XR2 87 
J 0
(-8937 2775);
DISPLAY 0.638298 (-8937 2775);
PAINT MONO (-8937 2775);
FORCEPROP 2 LAST $XR1 86 
J 0
(-8847 2775);
DISPLAY 0.638298 (-8847 2775);
PAINT MONO (-8847 2775);
FORCEPROP 2 LAST $XR0 159 
J 0
(-8757 2775);
DISPLAY 0.638298 (-8757 2775);
PAINT MONO (-8757 2775);
FORCEPROP 2 LAST CDS_LIB mstr_standard
J 0
(-8475 2775);
DISPLAY 0.808511 (-8475 2775);
DISPLAY INVISIBLE (-8475 2775);
FORCEPROP 1 LAST OFFPAGE TRUE
J 0
(-8150 2650);
DISPLAY 0.872340 (-8150 2650);
PAINT GREEN (-8150 2650);
DISPLAY INVISIBLE (-8150 2650);
FORCEPROP 1 LAST COMMENT_BODY TRUE
J 0
(-8350 2675);
DISPLAY 0.872340 (-8350 2675);
PAINT GREEN (-8350 2675);
DISPLAY INVISIBLE (-8350 2675);
FORCEPROP 2 LAST PATH I420
J 0
(-8750 2825);
DISPLAY 0.680851 (-8750 2825);
DISPLAY INVISIBLE (-8750 2825);
FORCEADD Q_RES..1
(-7825 2775);
FORCEPROP 1 LAST LOCATION R1
J 0
(-7875 2800);
DISPLAY 0.510638 (-7875 2800);
PAINT SKYBLUE (-7875 2800);
FORCEPROP 0 LAST $SEC 1
J 0
(-7875 2875);
DISPLAY 0.680851 (-7875 2875);
PAINT MONO (-7875 2875);
DISPLAY INVISIBLE (-7875 2875);
FORCEPROP 0 LAST CDS_SEC 1
J 0
(-7875 2875);
DISPLAY 0.680851 (-7875 2875);
DISPLAY INVISIBLE (-7875 2875);
FORCEPROP 1 LASTPIN (-7925 2775) $PN 1
J 0
(-7913 2787);
DISPLAY 0.787234 (-7913 2787);
PAINT MONO (-7913 2787);
FORCEPROP 1 LASTPIN (-7725 2775) $PN 2
J 0
(-7763 2787);
DISPLAY 0.787234 (-7763 2787);
PAINT MONO (-7763 2787);
FORCEPROP 1 LAST VALUE 49.9
J 2
(-7675 2850);
DISPLAY 0.510638 (-7675 2850);
PAINT SKYBLUE (-7675 2850);
FORCEPROP 2 LAST CDS_LIB pure_quanta
J 0
(-7825 2775);
DISPLAY INVISIBLE (-7825 2775);
FORCEPROP 1 LAST TOLERANCE 1%
J 0
(-7825 2675);
DISPLAY 0.978723 (-7825 2675);
DISPLAY INVISIBLE (-7825 2675);
FORCEPROP 1 LAST WATTAGE 1/16W
J 2
(-7850 2625);
DISPLAY 0.978723 (-7850 2625);
DISPLAY INVISIBLE (-7850 2625);
FORCEPROP 1 LAST PACK_TYPE 0402LF
J 0
(-7575 2625);
DISPLAY 0.978723 (-7575 2625);
DISPLAY INVISIBLE (-7575 2625);
FORCEPROP 1 LAST MATERIAL CHIP
J 0
(-7825 2625);
DISPLAY 0.978723 (-7825 2625);
DISPLAY INVISIBLE (-7825 2625);
FORCEPROP 1 LAST PATH I421
J 0
(-7875 2925);
DISPLAY 0.978723 (-7875 2925);
PAINT WHITE (-7875 2925);
DISPLAY INVISIBLE (-7875 2925);
FORCEPROP 1 LAST PART_NUMBER CS04992FB07
J 0
(-7875 2875);
DISPLAY 0.978723 (-7875 2875);
DISPLAY INVISIBLE (-7875 2875);
FORCEADD Q_RES..1
(-8175 3000);
FORCEPROP 1 LAST LOCATION R1676
J 0
(-8350 3000);
DISPLAY 0.510638 (-8350 3000);
FORCEPROP 2 LAST SEC 1
J 0
(-8225 3200);
DISPLAY 0.680851 (-8225 3200);
PAINT MONO (-8225 3200);
DISPLAY INVISIBLE (-8225 3200);
FORCEPROP 1 LASTPIN (-8275 3000) $PN 1
J 0
(-8263 3012);
DISPLAY 0.510638 (-8263 3012);
PAINT MONO (-8263 3012);
FORCEPROP 1 LASTPIN (-8075 3000) $PN 2
J 0
(-8113 3012);
DISPLAY 0.510638 (-8113 3012);
PAINT MONO (-8113 3012);
FORCEPROP 1 LAST VALUE 10
J 2
(-8025 3000);
DISPLAY 0.404255 (-8025 3000);
FORCEPROP 1 LAST MATERIAL CHIP
J 0
(-8275 2975);
DISPLAY 0.404255 (-8275 2975);
FORCEPROP 1 LAST PACK_TYPE 0402LF
J 0
(-8125 2975);
DISPLAY 0.404255 (-8125 2975);
FORCEPROP 1 LAST WATTAGE 1/16W
J 2
(-8200 2850);
DISPLAY 0.978723 (-8200 2850);
DISPLAY INVISIBLE (-8200 2850);
FORCEPROP 1 LAST TOLERANCE 1%
J 0
(-8175 2900);
DISPLAY 0.978723 (-8175 2900);
DISPLAY INVISIBLE (-8175 2900);
FORCEPROP 2 LAST CDS_LIB pure_quanta
J 0
(-8175 3000);
DISPLAY INVISIBLE (-8175 3000);
FORCEPROP 2 LAST SEC_TYPE 0402LF
J 0
(-8225 3200);
DISPLAY 0.680851 (-8225 3200);
DISPLAY INVISIBLE (-8225 3200);
FORCEPROP 1 LAST PATH I422
J 0
(-8225 3150);
DISPLAY 0.978723 (-8225 3150);
PAINT WHITE (-8225 3150);
DISPLAY INVISIBLE (-8225 3150);
FORCEPROP 1 LAST PART_NUMBER CS01002FB07
J 0
(-8225 3100);
DISPLAY 0.978723 (-8225 3100);
DISPLAY INVISIBLE (-8225 3100);
FORCEADD OFFPAGE..6
(-8850 2900);
FORCEPROP 2 LAST $XR5 159 
J 0
(-9219 2864);
DISPLAY 0.638298 (-9219 2864);
PAINT MONO (-9219 2864);
FORCEPROP 2 LAST $XR4 91 
J 0
(-9099 2864);
DISPLAY 0.638298 (-9099 2864);
PAINT MONO (-9099 2864);
FORCEPROP 2 LAST $XR3 90 
J 0
(-9369 2900);
DISPLAY 0.638298 (-9369 2900);
PAINT MONO (-9369 2900);
FORCEPROP 2 LAST $XR2 88 
J 0
(-9279 2900);
DISPLAY 0.638298 (-9279 2900);
PAINT MONO (-9279 2900);
FORCEPROP 2 LAST $XR1 87 
J 0
(-9189 2900);
DISPLAY 0.638298 (-9189 2900);
PAINT MONO (-9189 2900);
FORCEPROP 2 LAST $XR0 86 
J 0
(-9099 2900);
DISPLAY 0.638298 (-9099 2900);
PAINT MONO (-9099 2900);
FORCEPROP 2 LAST CDS_LIB mstr_standard
J 0
(-8850 2900);
DISPLAY 0.808511 (-8850 2900);
DISPLAY INVISIBLE (-8850 2900);
FORCEPROP 1 LAST OFFPAGE TRUE
J 0
(-8525 2775);
DISPLAY 0.872340 (-8525 2775);
PAINT GREEN (-8525 2775);
DISPLAY INVISIBLE (-8525 2775);
FORCEPROP 1 LAST COMMENT_BODY TRUE
J 0
(-8750 2825);
DISPLAY 0.872340 (-8750 2825);
PAINT GREEN (-8750 2825);
DISPLAY INVISIBLE (-8750 2825);
FORCEPROP 2 LAST PATH I423
J 0
(-9125 2950);
DISPLAY 0.680851 (-9125 2950);
DISPLAY INVISIBLE (-9125 2950);
FORCEADD QUANTA_TITLE_BLOCK_C..1
(-100 100);
FORCEPROP 0 LAST CDS_CON_LAST_MODIFIED Thu Sep 14 16:12:06 2023
J 0
(-1985 115);
DISPLAY INVISIBLE (-1985 115);
FORCEPROP 1 LAST CUSTOM_TXT_CDS <CON_LAST_MODIFIED>
J 0
(-1985 115);
DISPLAY 0.978723 (-1985 115);
FORCEPROP 2 LAST CUSTOM_TXT_CDS <XR_PAGE_TITLE>
J 0
(-7990 5350);
DISPLAY 0.638298 (-7990 5350);
PAINT PINK (-7990 5350);
DISPLAY INVISIBLE (-7990 5350);
FORCEPROP 1 LAST CUSTOM_TXT_CDS <NAME_2>
J 0
(-3275 150);
FORCEPROP 1 LAST CUSTOM_TXT_CDS <NAME_1>
J 0
(-3275 275);
FORCEPROP 1 LAST CUSTOM_TXT_CDS <Q_NUMBER>
J 0
(-1503 203);
DISPLAY 1.212766 (-1503 203);
FORCEPROP 1 LAST CUSTOM_TXT_CDS <Q_PROJ>
J 0
(-2482 202);
DISPLAY 1.212766 (-2482 202);
FORCEPROP 1 LAST CUSTOM_TXT_CDS <Q_REV>
J 0
(-284 203);
DISPLAY 1.212766 (-284 203);
FORCEPROP 1 LAST CUSTOM_TXT_CDS <CON_PAGE_NUM> OF <CON_TOTAL_PAGES>
J 0
(-546 118);
DISPLAY 0.978723 (-546 118);
FORCEPROP 1 LAST Q_TITLE DDR5 - CPU0 CHD
J 0
(-9425 150);
DISPLAY 2.446809 (-9425 150);
PAINT GREEN (-9425 150);
FORCEPROP 2 LAST PAGE_BORDER TRUE
J 0
(-7990 5350);
DISPLAY 0.638298 (-7990 5350);
PAINT PINK (-7990 5350);
DISPLAY INVISIBLE (-7990 5350);
FORCEPROP 1 LAST CDS_LMAN_SYM_OUTLINE -9475,6775,100,-125
J 0
(-100 100);
DISPLAY 0.468085 (-100 100);
PAINT GREEN (-100 100);
DISPLAY INVISIBLE (-100 100);
FORCEPROP 2 LAST CDS_LIB pure_quanta
J 0
(-100 100);
DISPLAY INVISIBLE (-100 100);
FORCEPROP 2 LAST CDS_XR_PAGE_TITLE CR-89 : @T6G_MB_LIB.T6G(SCH_1):PAGE89
J 0
(-7990 5350);
DISPLAY 0.638298 (-7990 5350);
PAINT PINK (-7990 5350);
DISPLAY INVISIBLE (-7990 5350);
FORCEPROP 1 LAST Q_DEPT BU9
J 1
(-3863 149);
DISPLAY 1.957447 (-3863 149);
PAINT GREEN (-3863 149);
DISPLAY INVISIBLE (-3863 149);
FORCEPROP 1 LAST COMMENT_BODY TRUE
J 0
(-88 87);
DISPLAY 0.978723 (-88 87);
PAINT GREEN (-88 87);
DISPLAY INVISIBLE (-88 87);
FORCEADD DNS..2
(-8350 2450);
PAINT RED (-8350 2450);
FORCEPROP 2 LAST CDS_LIB mstr_misc
J 0
(-8350 2450);
DISPLAY INVISIBLE (-8350 2450);
FORCEPROP 1 LAST COMMENT_BODY TRUE
R 1
J 0
(-8275 2225);
DISPLAY 0.872340 (-8275 2225);
PAINT PEACH (-8275 2225);
DISPLAY INVISIBLE (-8275 2225);
WIRE 17 -1 (-6025 5525)(-6025 5475);
WIRE 17 -1 (-6025 5575)(-6025 5525);
WIRE 17 -1 (-6025 5475)(-6025 5425);
WIRE 17 -1 (-6025 5425)(-6025 5375);
WIRE 17 -1 (-6025 5600)(-6025 5575);
WIRE 17 -1 (-6025 5600)(-5575 5600);
FORCEPROP 2 LAST SIG_NAME M_D_CPU0_SA_DQ<31:0>
J 0
(-6010 5635);
DISPLAY 0.489362 (-6010 5635);
WIRE 17 -1 (-6025 4625)(-6025 4675);
WIRE 17 -1 (-6025 4625)(-6025 4575);
WIRE 17 -1 (-6025 4675)(-6025 4725);
WIRE 17 -1 (-6025 4725)(-6025 4775);
WIRE 17 -1 (-6025 4575)(-6025 4525);
WIRE 17 -1 (-6025 4525)(-6025 4475);
WIRE 17 -1 (-6025 4775)(-6025 4825);
WIRE 17 -1 (-6025 4875)(-6025 4825);
WIRE 17 -1 (-6025 4475)(-6025 4425);
WIRE 17 -1 (-6025 4425)(-6025 4375);
WIRE 17 -1 (-6025 4925)(-6025 4875);
WIRE 17 -1 (-6025 4975)(-6025 4925);
WIRE 17 -1 (-6025 4375)(-6025 4325);
WIRE 17 -1 (-6025 4325)(-6025 4275);
WIRE 17 -1 (-6025 5025)(-6025 4975);
WIRE 17 -1 (-6025 5075)(-6025 5025);
WIRE 17 -1 (-6025 4275)(-6025 4225);
WIRE 17 -1 (-6025 4175)(-6025 4225);
WIRE 17 -1 (-6025 5125)(-6025 5075);
WIRE 17 -1 (-6025 5175)(-6025 5125);
WIRE 17 -1 (-6025 4125)(-6025 4175);
WIRE 17 -1 (-6025 4075)(-6025 4125);
WIRE 17 -1 (-6025 5225)(-6025 5175);
WIRE 17 -1 (-6025 5275)(-6025 5225);
WIRE 17 -1 (-6025 4025)(-6025 4075);
WIRE 17 -1 (-6025 5325)(-6025 5275);
WIRE 17 -1 (-6025 5375)(-6025 5325);
WIRE 17 -1 (-3450 4625)(-3450 4600);
WIRE 17 -1 (-3450 4625)(-2750 4625);
FORCEPROP 2 LAST SIG_NAME M_D_CPU0_SA_DQS_DN<9:0>
J 0
(-3385 4635);
DISPLAY 0.489362 (-3385 4635);
WIRE 17 -1 (-3650 3600)(-3650 3500);
WIRE 17 -1 (-3650 3625)(-3650 3600);
WIRE 17 -1 (-3650 3500)(-3650 3400);
WIRE 17 -1 (-3650 3400)(-3650 3300);
WIRE 17 -1 (-3650 3625)(-2750 3625);
FORCEPROP 2 LAST SIG_NAME M_D_CPU0_SB_DQS_DP<9:0>
J 0
(-3385 3635);
DISPLAY 0.489362 (-3385 3635);
WIRE 17 -1 (-3450 3575)(-3450 3550);
WIRE 17 -1 (-3450 3575)(-2750 3575);
FORCEPROP 2 LAST SIG_NAME M_D_CPU0_SB_DQS_DN<9:0>
J 0
(-3385 3585);
DISPLAY 0.489362 (-3385 3585);
WIRE 17 -1 (-3450 3800)(-3450 3700);
WIRE 17 -1 (-3450 3900)(-3450 3800);
WIRE 17 -1 (-3450 3900)(-3450 4000);
WIRE 17 -1 (-3450 4000)(-3450 4100);
WIRE 17 -1 (-3450 4100)(-3450 4200);
WIRE 17 -1 (-3450 4300)(-3450 4200);
WIRE 17 -1 (-3450 4400)(-3450 4300);
WIRE 17 -1 (-3450 4500)(-3450 4400);
WIRE 17 -1 (-3450 4600)(-3450 4500);
WIRE 17 -1 (-3650 3950)(-3650 3850);
WIRE 17 -1 (-3650 3950)(-3650 4050);
WIRE 17 -1 (-3650 3850)(-3650 3750);
WIRE 17 -1 (-3650 4050)(-3650 4150);
WIRE 17 -1 (-3650 4150)(-3650 4250);
WIRE 17 -1 (-3650 4350)(-3650 4250);
WIRE 17 -1 (-3650 4450)(-3650 4350);
WIRE 17 -1 (-3650 4550)(-3650 4450);
WIRE 17 -1 (-3650 4650)(-3650 4550);
WIRE 17 -1 (-3650 4675)(-3650 4650);
WIRE 17 -1 (-3650 4675)(-2750 4675);
FORCEPROP 2 LAST SIG_NAME M_D_CPU0_SA_DQS_DP<9:0>
J 0
(-3385 4685);
DISPLAY 0.489362 (-3385 4685);
WIRE 17 -1 (-3450 3450)(-3450 3350);
WIRE 17 -1 (-3450 3550)(-3450 3450);
WIRE 17 -1 (-3450 3350)(-3450 3250);
WIRE 17 -1 (-3450 3250)(-3450 3150);
WIRE 17 -1 (-3650 3300)(-3650 3200);
WIRE 17 -1 (-3650 3100)(-3650 3200);
WIRE 17 -1 (-3650 3000)(-3650 3100);
WIRE 17 -1 (-3650 2900)(-3650 3000);
WIRE 17 -1 (-3450 3050)(-3450 3150);
WIRE 17 -1 (-3450 2950)(-3450 3050);
WIRE 17 -1 (-3450 2850)(-3450 2950);
WIRE 17 -1 (-3650 2900)(-3650 2800);
WIRE 17 -1 (-3450 2850)(-3450 2750);
WIRE 17 -1 (-3650 2800)(-3650 2700);
WIRE 17 -1 (-3450 2750)(-3450 2650);
WIRE 17 -1 (-7825 5525)(-7825 5575);
WIRE 17 -1 (-7825 5475)(-7825 5525);
WIRE 17 -1 (-7825 5575)(-7825 5600);
WIRE 17 -1 (-7825 5600)(-8325 5600);
FORCEPROP 2 LAST SIG_NAME M_D_CPU0_SA_CA<6:0>
J 0
(-8310 5610);
DISPLAY 0.489362 (-8310 5610);
WIRE 17 -1 (-6025 2375)(-6025 2425);
WIRE 17 -1 (-6025 2425)(-6025 2475);
WIRE 17 -1 (-6025 2475)(-6025 2525);
WIRE 17 -1 (-6025 2525)(-6025 2575);
WIRE 17 -1 (-6025 2625)(-6025 2575);
WIRE 17 -1 (-6025 2675)(-6025 2625);
WIRE 17 -1 (-6025 2725)(-6025 2675);
WIRE 17 -1 (-6025 2775)(-6025 2725);
WIRE 17 -1 (-6025 2825)(-6025 2775);
WIRE 17 -1 (-6025 2875)(-6025 2825);
WIRE 17 -1 (-6025 2925)(-6025 2875);
WIRE 17 -1 (-6025 2975)(-6025 2925);
WIRE 17 -1 (-6025 2975)(-6025 3025);
WIRE 17 -1 (-6025 3025)(-6025 3075);
WIRE 17 -1 (-6025 3075)(-6025 3125);
WIRE 17 -1 (-6025 3125)(-6025 3175);
WIRE 17 -1 (-6025 3225)(-6025 3175);
WIRE 17 -1 (-6025 3275)(-6025 3225);
WIRE 17 -1 (-6025 3325)(-6025 3275);
WIRE 17 -1 (-6025 3375)(-6025 3325);
WIRE 17 -1 (-6025 3425)(-6025 3375);
WIRE 17 -1 (-6025 3475)(-6025 3425);
WIRE 17 -1 (-6025 3525)(-6025 3475);
WIRE 17 -1 (-6025 3575)(-6025 3525);
WIRE 17 -1 (-6025 3625)(-6025 3575);
WIRE 17 -1 (-6025 3675)(-6025 3625);
WIRE 17 -1 (-6025 3725)(-6025 3675);
WIRE 17 -1 (-6025 3775)(-6025 3725);
WIRE 17 -1 (-6025 3825)(-6025 3775);
WIRE 17 -1 (-6025 3875)(-6025 3825);
WIRE 17 -1 (-6025 3925)(-6025 3875);
WIRE 17 -1 (-6025 3950)(-6025 3925);
WIRE 17 -1 (-6025 3950)(-5575 3950);
FORCEPROP 2 LAST SIG_NAME M_D_CPU0_SB_DQ<31:0>
J 0
(-6010 3985);
DISPLAY 0.489362 (-6010 3985);
WIRE 17 -1 (-7825 3425)(-7825 3475);
WIRE 17 -1 (-7825 3375)(-7825 3425);
WIRE 17 -1 (-7825 3475)(-7825 3525);
WIRE 17 -1 (-7825 3525)(-7825 3575);
WIRE 17 -1 (-7825 3625)(-7825 3575);
WIRE 17 -1 (-7825 3625)(-7825 3675);
WIRE 17 -1 (-7825 3725)(-7825 3675);
WIRE 17 -1 (-7825 3725)(-7825 3750);
WIRE 17 -1 (-7825 3750)(-8325 3750);
FORCEPROP 2 LAST SIG_NAME M_D_CPU0_SB_CB<7:0>
J 0
(-8275 3760);
DISPLAY 0.489362 (-8275 3760);
WIRE 17 -1 (-7825 3825)(-7825 3875);
WIRE 17 -1 (-7825 3875)(-7825 3925);
WIRE 17 -1 (-7825 3925)(-7825 3975);
WIRE 17 -1 (-7825 3975)(-7825 4025);
WIRE 17 -1 (-7825 4075)(-7825 4025);
WIRE 17 -1 (-7825 4075)(-7825 4125);
WIRE 17 -1 (-7825 4175)(-7825 4125);
WIRE 17 -1 (-7825 4175)(-7825 4200);
WIRE 17 -1 (-7825 4200)(-8325 4200);
FORCEPROP 2 LAST SIG_NAME M_D_CPU0_SA_CB<7:0>
J 0
(-8275 4210);
DISPLAY 0.489362 (-8275 4210);
WIRE 17 -1 (-7825 5175)(-7825 5200);
WIRE 17 -1 (-7825 5125)(-7825 5175);
WIRE 17 -1 (-7825 5200)(-8325 5200);
FORCEPROP 2 LAST SIG_NAME M_D_CPU0_SB_CA<6:0>
J 0
(-8310 5210);
DISPLAY 0.489362 (-8310 5210);
WIRE 17 -1 (-7825 5075)(-7825 5125);
WIRE 17 -1 (-7825 5025)(-7825 5075);
WIRE 17 -1 (-7825 4975)(-7825 5025);
WIRE 17 -1 (-7825 4925)(-7825 4975);
WIRE 17 -1 (-7825 5425)(-7825 5475);
WIRE 17 -1 (-7825 5375)(-7825 5425);
WIRE 17 -1 (-7825 5325)(-7825 5375);
WIRE 17 -1 (-7825 4875)(-7825 4925);
WIRE 17 -1 (-7825 5275)(-7825 5325);
WIRE 16 -1 (-6450 1225)(-6450 1325);
WIRE 16 -1 (-8600 3200)(-8600 3275);
WIRE 16 -1 (-8375 2550)(-8375 2575);
WIRE 16 -1 (-7525 3350)(-7725 3350);
WIRE 16 -1 (-7925 2775)(-8425 2775);
FORCEPROP 2 LAST SIG_NAME I3C_SPD_DDRAF_CPU0_SCL
J 0
(-8460 2785);
DISPLAY 0.489362 (-8460 2785);
WIRE 16 -1 (-7525 3250)(-8050 3250);
FORCEPROP 2 LAST SIG_NAME M_D_CPU0_RESET_N
J 0
(-8035 3260);
DISPLAY 0.489362 (-8035 3260);
WIRE 16 -1 (-7625 2950)(-7625 2775);
WIRE 16 -1 (-7525 2950)(-7625 2950);
FORCEPROP 2 LAST SIG_NAME I3C_SPD_DDRD_CPU0_SCL
J 0
(-7985 2900);
DISPLAY 0.361702 (-7985 2900);
FORCEPROP 2 LASTPROP $XRERR UNIQUE?
J 0
(-8225 2900);
DISPLAY 0.638298 (-8225 2900);
PAINT MONO (-8225 2900);
DISPLAY INVISIBLE (-8225 2900);
WIRE 16 -1 (-7625 2775)(-7725 2775);
WIRE 16 -1 (-2375 5775)(-2250 5775);
WIRE 16 -1 (-2375 5775)(-2375 5675);
WIRE 16 -1 (-2375 5775)(-2950 5775);
WIRE 16 -1 (-2250 5350)(-2250 5775);
WIRE 16 -1 (-1950 5350)(-2250 5350);
WIRE 16 -1 (-2250 5300)(-2250 5350);
WIRE 16 -1 (-2950 5675)(-2950 5775);
WIRE 16 -1 (-2950 5775)(-2950 5850);
WIRE 16 -1 (-1950 5300)(-2250 5300);
WIRE 16 -1 (-2250 5300)(-2250 5250);
WIRE 16 -1 (-2250 5250)(-1950 5250);
WIRE 16 -1 (-2375 5350)(-2375 5475);
WIRE 16 -1 (-2375 5350)(-2950 5350);
WIRE 16 -1 (-2950 5350)(-2950 5475);
WIRE 16 -1 (-2950 5350)(-2950 5275);
WIRE 16 -1 (-450 2200)(-450 2100);
WIRE 16 -1 (-450 2250)(-450 2200);
WIRE 16 -1 (-450 2200)(-750 2200);
WIRE 16 -1 (-450 2100)(-450 2050);
WIRE 16 -1 (-450 2100)(-750 2100);
WIRE 16 -1 (-450 2050)(-750 2050);
WIRE 16 -1 (-450 2050)(-450 2000);
WIRE 16 -1 (-450 2300)(-450 2250);
WIRE 16 -1 (-450 2250)(-750 2250);
WIRE 16 -1 (-450 2350)(-450 2300);
WIRE 16 -1 (-450 2300)(-750 2300);
WIRE 16 -1 (-450 2000)(-450 1800);
WIRE 16 -1 (-450 2000)(-750 2000);
WIRE 16 -1 (-450 2400)(-450 2350);
WIRE 16 -1 (-450 2350)(-750 2350);
WIRE 16 -1 (-450 2450)(-450 2400);
WIRE 16 -1 (-450 2400)(-750 2400);
WIRE 16 -1 (-450 2500)(-450 2450);
WIRE 16 -1 (-450 2450)(-750 2450);
WIRE 16 -1 (-450 2550)(-450 2500);
WIRE 16 -1 (-450 2500)(-750 2500);
WIRE 16 -1 (-450 2600)(-450 2550);
WIRE 16 -1 (-450 2550)(-750 2550);
WIRE 16 -1 (-450 2650)(-450 2600);
WIRE 16 -1 (-450 2600)(-750 2600);
WIRE 16 -1 (-450 2700)(-450 2650);
WIRE 16 -1 (-450 2650)(-750 2650);
WIRE 16 -1 (-450 2750)(-450 2700);
WIRE 16 -1 (-450 2700)(-750 2700);
WIRE 16 -1 (-450 2800)(-450 2750);
WIRE 16 -1 (-450 2750)(-750 2750);
WIRE 16 -1 (-450 2850)(-450 2800);
WIRE 16 -1 (-450 2800)(-750 2800);
WIRE 16 -1 (-450 2900)(-450 2850);
WIRE 16 -1 (-450 2850)(-750 2850);
WIRE 16 -1 (-450 2950)(-450 2900);
WIRE 16 -1 (-450 2900)(-750 2900);
WIRE 16 -1 (-450 3000)(-450 2950);
WIRE 16 -1 (-450 2950)(-750 2950);
WIRE 16 -1 (-450 3050)(-450 3000);
WIRE 16 -1 (-450 3000)(-750 3000);
WIRE 16 -1 (-450 3100)(-450 3050);
WIRE 16 -1 (-450 3050)(-750 3050);
WIRE 16 -1 (-450 3150)(-450 3100);
WIRE 16 -1 (-450 3100)(-750 3100);
WIRE 16 -1 (-450 3200)(-450 3150);
WIRE 16 -1 (-450 3150)(-750 3150);
WIRE 16 -1 (-450 3250)(-450 3200);
WIRE 16 -1 (-450 3200)(-750 3200);
WIRE 16 -1 (-450 3300)(-450 3250);
WIRE 16 -1 (-450 3250)(-750 3250);
WIRE 16 -1 (-450 3350)(-450 3300);
WIRE 16 -1 (-450 3300)(-750 3300);
WIRE 16 -1 (-450 3400)(-450 3350);
WIRE 16 -1 (-450 3350)(-750 3350);
WIRE 16 -1 (-450 3450)(-450 3400);
WIRE 16 -1 (-450 3400)(-750 3400);
WIRE 16 -1 (-450 3500)(-450 3450);
WIRE 16 -1 (-450 3450)(-750 3450);
WIRE 16 -1 (-450 3550)(-450 3500);
WIRE 16 -1 (-450 3500)(-750 3500);
WIRE 16 -1 (-450 3600)(-450 3550);
WIRE 16 -1 (-450 3550)(-750 3550);
WIRE 16 -1 (-450 3650)(-450 3600);
WIRE 16 -1 (-450 3600)(-750 3600);
WIRE 16 -1 (-450 3700)(-450 3650);
WIRE 16 -1 (-450 3650)(-750 3650);
WIRE 16 -1 (-450 3750)(-450 3700);
WIRE 16 -1 (-450 3700)(-750 3700);
WIRE 16 -1 (-450 3800)(-450 3750);
WIRE 16 -1 (-450 3750)(-750 3750);
WIRE 16 -1 (-450 3850)(-450 3800);
WIRE 16 -1 (-450 3800)(-750 3800);
WIRE 16 -1 (-450 3900)(-450 3850);
WIRE 16 -1 (-450 3850)(-750 3850);
WIRE 16 -1 (-450 3950)(-450 3900);
WIRE 16 -1 (-450 3900)(-750 3900);
WIRE 16 -1 (-450 4000)(-450 3950);
WIRE 16 -1 (-450 3950)(-750 3950);
WIRE 16 -1 (-450 4050)(-450 4000);
WIRE 16 -1 (-450 4000)(-750 4000);
WIRE 16 -1 (-450 4100)(-450 4050);
WIRE 16 -1 (-450 4050)(-750 4050);
WIRE 16 -1 (-450 4150)(-450 4100);
WIRE 16 -1 (-450 4100)(-750 4100);
WIRE 16 -1 (-450 4200)(-450 4150);
WIRE 16 -1 (-450 4150)(-750 4150);
WIRE 16 -1 (-450 4250)(-450 4200);
WIRE 16 -1 (-450 4200)(-750 4200);
WIRE 16 -1 (-450 4300)(-450 4250);
WIRE 16 -1 (-450 4250)(-750 4250);
WIRE 16 -1 (-450 4350)(-450 4300);
WIRE 16 -1 (-450 4300)(-750 4300);
WIRE 16 -1 (-450 4400)(-450 4350);
WIRE 16 -1 (-450 4350)(-750 4350);
WIRE 16 -1 (-450 4450)(-450 4400);
WIRE 16 -1 (-450 4400)(-750 4400);
WIRE 16 -1 (-450 4500)(-450 4450);
WIRE 16 -1 (-450 4450)(-750 4450);
WIRE 16 -1 (-450 4550)(-450 4500);
WIRE 16 -1 (-450 4500)(-750 4500);
WIRE 16 -1 (-450 4600)(-450 4550);
WIRE 16 -1 (-450 4550)(-750 4550);
WIRE 16 -1 (-450 4650)(-450 4600);
WIRE 16 -1 (-450 4600)(-750 4600);
WIRE 16 -1 (-450 4700)(-450 4650);
WIRE 16 -1 (-450 4650)(-750 4650);
WIRE 16 -1 (-450 4750)(-450 4700);
WIRE 16 -1 (-450 4700)(-750 4700);
WIRE 16 -1 (-450 4800)(-450 4750);
WIRE 16 -1 (-450 4750)(-750 4750);
WIRE 16 -1 (-450 4850)(-450 4800);
WIRE 16 -1 (-450 4800)(-750 4800);
WIRE 16 -1 (-450 4900)(-450 4850);
WIRE 16 -1 (-450 4850)(-750 4850);
WIRE 16 -1 (-450 4950)(-450 4900);
WIRE 16 -1 (-450 4900)(-750 4900);
WIRE 16 -1 (-450 5000)(-450 4950);
WIRE 16 -1 (-450 4950)(-750 4950);
WIRE 16 -1 (-450 5050)(-450 5000);
WIRE 16 -1 (-450 5000)(-750 5000);
WIRE 16 -1 (-450 5100)(-450 5050);
WIRE 16 -1 (-450 5050)(-750 5050);
WIRE 16 -1 (-450 5150)(-450 5100);
WIRE 16 -1 (-450 5100)(-750 5100);
WIRE 16 -1 (-450 5200)(-450 5150);
WIRE 16 -1 (-450 5150)(-750 5150);
WIRE 16 -1 (-450 5250)(-450 5200);
WIRE 16 -1 (-450 5200)(-750 5200);
WIRE 16 -1 (-450 5300)(-450 5250);
WIRE 16 -1 (-450 5250)(-750 5250);
WIRE 16 -1 (-450 5350)(-450 5300);
WIRE 16 -1 (-450 5300)(-750 5300);
WIRE 16 -1 (-450 5350)(-750 5350);
WIRE 16 -1 (-1950 2150)(-2250 2150);
WIRE 16 -1 (-2250 2200)(-2250 2150);
WIRE 16 -1 (-2250 2150)(-2250 2100);
WIRE 16 -1 (-1950 2100)(-2250 2100);
WIRE 16 -1 (-2250 2100)(-2250 2000);
WIRE 16 -1 (-1950 2200)(-2250 2200);
WIRE 16 -1 (-2250 2250)(-2250 2200);
WIRE 16 -1 (-1950 2250)(-2250 2250);
WIRE 16 -1 (-2250 2300)(-2250 2250);
WIRE 16 -1 (-1950 2300)(-2250 2300);
WIRE 16 -1 (-2250 2350)(-2250 2300);
WIRE 16 -1 (-1950 2350)(-2250 2350);
WIRE 16 -1 (-2250 2400)(-2250 2350);
WIRE 16 -1 (-1950 2400)(-2250 2400);
WIRE 16 -1 (-2250 2450)(-2250 2400);
WIRE 16 -1 (-1950 2450)(-2250 2450);
WIRE 16 -1 (-2250 2500)(-2250 2450);
WIRE 16 -1 (-1950 2500)(-2250 2500);
WIRE 16 -1 (-2250 2550)(-2250 2500);
WIRE 16 -1 (-1950 2550)(-2250 2550);
WIRE 16 -1 (-2250 2600)(-2250 2550);
WIRE 16 -1 (-1950 2600)(-2250 2600);
WIRE 16 -1 (-2250 2650)(-2250 2600);
WIRE 16 -1 (-1950 2650)(-2250 2650);
WIRE 16 -1 (-2250 2700)(-2250 2650);
WIRE 16 -1 (-1950 2700)(-2250 2700);
WIRE 16 -1 (-2250 2750)(-2250 2700);
WIRE 16 -1 (-1950 2750)(-2250 2750);
WIRE 16 -1 (-2250 2800)(-2250 2750);
WIRE 16 -1 (-1950 2800)(-2250 2800);
WIRE 16 -1 (-2250 2850)(-2250 2800);
WIRE 16 -1 (-1950 2850)(-2250 2850);
WIRE 16 -1 (-2250 2900)(-2250 2850);
WIRE 16 -1 (-1950 2900)(-2250 2900);
WIRE 16 -1 (-2250 2950)(-2250 2900);
WIRE 16 -1 (-1950 2950)(-2250 2950);
WIRE 16 -1 (-2250 3000)(-2250 2950);
WIRE 16 -1 (-1950 3000)(-2250 3000);
WIRE 16 -1 (-2250 3050)(-2250 3000);
WIRE 16 -1 (-1950 3050)(-2250 3050);
WIRE 16 -1 (-2250 3100)(-2250 3050);
WIRE 16 -1 (-1950 3100)(-2250 3100);
WIRE 16 -1 (-2250 3150)(-2250 3100);
WIRE 16 -1 (-1950 3150)(-2250 3150);
WIRE 16 -1 (-2250 3200)(-2250 3150);
WIRE 16 -1 (-1950 3200)(-2250 3200);
WIRE 16 -1 (-2250 3250)(-2250 3200);
WIRE 16 -1 (-1950 3250)(-2250 3250);
WIRE 16 -1 (-2250 3300)(-2250 3250);
WIRE 16 -1 (-1950 3300)(-2250 3300);
WIRE 16 -1 (-2250 3350)(-2250 3300);
WIRE 16 -1 (-1950 3350)(-2250 3350);
WIRE 16 -1 (-2250 3400)(-2250 3350);
WIRE 16 -1 (-1950 3400)(-2250 3400);
WIRE 16 -1 (-2250 3450)(-2250 3400);
WIRE 16 -1 (-1950 3450)(-2250 3450);
WIRE 16 -1 (-2250 3500)(-2250 3450);
WIRE 16 -1 (-1950 3500)(-2250 3500);
WIRE 16 -1 (-2250 3550)(-2250 3500);
WIRE 16 -1 (-1950 3550)(-2250 3550);
WIRE 16 -1 (-2250 3600)(-2250 3550);
WIRE 16 -1 (-1950 3600)(-2250 3600);
WIRE 16 -1 (-2250 3650)(-2250 3600);
WIRE 16 -1 (-1950 3650)(-2250 3650);
WIRE 16 -1 (-2250 3700)(-2250 3650);
WIRE 16 -1 (-1950 3700)(-2250 3700);
WIRE 16 -1 (-2250 3750)(-2250 3700);
WIRE 16 -1 (-1950 3750)(-2250 3750);
WIRE 16 -1 (-2250 3800)(-2250 3750);
WIRE 16 -1 (-1950 3800)(-2250 3800);
WIRE 16 -1 (-2250 3850)(-2250 3800);
WIRE 16 -1 (-1950 3850)(-2250 3850);
WIRE 16 -1 (-2250 3900)(-2250 3850);
WIRE 16 -1 (-1950 3900)(-2250 3900);
WIRE 16 -1 (-2250 3950)(-2250 3900);
WIRE 16 -1 (-1950 3950)(-2250 3950);
WIRE 16 -1 (-2250 4000)(-2250 3950);
WIRE 16 -1 (-1950 4000)(-2250 4000);
WIRE 16 -1 (-2250 4050)(-2250 4000);
WIRE 16 -1 (-2250 4100)(-2250 4050);
WIRE 16 -1 (-1950 4050)(-2250 4050);
WIRE 16 -1 (-1950 4100)(-2250 4100);
WIRE 16 -1 (-2250 4150)(-2250 4100);
WIRE 16 -1 (-1950 4150)(-2250 4150);
WIRE 16 -1 (-2250 4200)(-2250 4150);
WIRE 16 -1 (-1950 4200)(-2250 4200);
WIRE 16 -1 (-2250 4250)(-2250 4200);
WIRE 16 -1 (-1950 4250)(-2250 4250);
WIRE 16 -1 (-2250 4300)(-2250 4250);
WIRE 16 -1 (-1950 4300)(-2250 4300);
WIRE 16 -1 (-2250 4350)(-2250 4300);
WIRE 16 -1 (-1950 4350)(-2250 4350);
WIRE 16 -1 (-2250 4400)(-2250 4350);
WIRE 16 -1 (-1950 4400)(-2250 4400);
WIRE 16 -1 (-2250 4450)(-2250 4400);
WIRE 16 -1 (-1950 4450)(-2250 4450);
WIRE 16 -1 (-2250 4500)(-2250 4450);
WIRE 16 -1 (-1950 4500)(-2250 4500);
WIRE 16 -1 (-2250 4550)(-2250 4500);
WIRE 16 -1 (-1950 4550)(-2250 4550);
WIRE 16 -1 (-2250 4600)(-2250 4550);
WIRE 16 -1 (-1950 4600)(-2250 4600);
WIRE 16 -1 (-2250 4650)(-2250 4600);
WIRE 16 -1 (-1950 4650)(-2250 4650);
WIRE 16 -1 (-2250 4700)(-2250 4650);
WIRE 16 -1 (-1950 4700)(-2250 4700);
WIRE 16 -1 (-2250 4750)(-2250 4700);
WIRE 16 -1 (-1950 4750)(-2250 4750);
WIRE 16 -1 (-2250 4800)(-2250 4750);
WIRE 16 -1 (-1950 4800)(-2250 4800);
WIRE 16 -1 (-2250 4850)(-2250 4800);
WIRE 16 -1 (-1950 4850)(-2250 4850);
WIRE 16 -1 (-2250 4900)(-2250 4850);
WIRE 16 -1 (-1950 4900)(-2250 4900);
WIRE 16 -1 (-2250 4950)(-2250 4900);
WIRE 16 -1 (-1950 4950)(-2250 4950);
WIRE 16 -1 (-2250 5000)(-2250 4950);
WIRE 16 -1 (-1950 5000)(-2250 5000);
WIRE 16 -1 (-2250 5050)(-2250 5000);
WIRE 16 -1 (-1950 5050)(-2250 5050);
WIRE 16 -1 (-2250 5100)(-2250 5050);
WIRE 16 -1 (-1950 5100)(-2250 5100);
WIRE 16 -1 (-2250 5150)(-2250 5100);
WIRE 16 -1 (-1950 5150)(-2250 5150);
WIRE 16 -1 (-2250 5200)(-2250 5150);
WIRE 16 -1 (-1950 5200)(-2250 5200);
WIRE 16 -1 (-6450 1600)(-6450 1525);
WIRE 16 -1 (-6450 1600)(-7175 1600);
FORCEPROP 2 LAST SIG_NAME PD_CHD_CPU0_DIMM_SAA
J 0
(-7160 1610);
DISPLAY 0.489362 (-7160 1610);
WIRE 16 -1 (-7525 4150)(-7725 4150);
WIRE 16 -1 (-7525 4000)(-7725 4000);
WIRE 16 -1 (-7525 3850)(-7725 3850);
WIRE 16 -1 (-7525 3700)(-7725 3700);
WIRE 16 -1 (-7525 5250)(-7725 5250);
WIRE 16 -1 (-7525 4850)(-7725 4850);
WIRE 16 -1 (-7525 5300)(-7725 5300);
WIRE 16 -1 (-7525 4900)(-7725 4900);
WIRE 16 -1 (-7525 5350)(-7725 5350);
WIRE 16 -1 (-7525 4950)(-7725 4950);
WIRE 16 -1 (-7525 5400)(-7725 5400);
WIRE 16 -1 (-7525 5000)(-7725 5000);
WIRE 16 -1 (-7525 5450)(-7725 5450);
WIRE 16 -1 (-7525 5050)(-7725 5050);
WIRE 16 -1 (-7525 5500)(-7725 5500);
WIRE 16 -1 (-7525 5100)(-7725 5100);
WIRE 16 -1 (-7525 5150)(-7725 5150);
WIRE 16 -1 (-7525 4100)(-7725 4100);
WIRE 16 -1 (-7525 4050)(-7725 4050);
WIRE 16 -1 (-7525 3950)(-7725 3950);
WIRE 16 -1 (-7525 3900)(-7725 3900);
WIRE 16 -1 (-7525 3800)(-7725 3800);
WIRE 16 -1 (-7525 3650)(-7725 3650);
WIRE 16 -1 (-7525 3600)(-7725 3600);
WIRE 16 -1 (-7525 3550)(-7725 3550);
WIRE 16 -1 (-7525 3500)(-7725 3500);
WIRE 16 -1 (-7525 3450)(-7725 3450);
WIRE 16 -1 (-7525 3400)(-7725 3400);
WIRE 16 -1 (-7525 4250)(-8325 4250);
FORCEPROP 2 LAST SIG_NAME M_D_CPU0_CLK_DN<0>
J 0
(-8275 4260);
DISPLAY 0.489362 (-8275 4260);
WIRE 16 -1 (-7525 4300)(-8325 4300);
FORCEPROP 2 LAST SIG_NAME M_D_CPU0_CLK_DP<0>
J 0
(-8275 4310);
DISPLAY 0.489362 (-8275 4310);
WIRE 16 -1 (-7525 4550)(-8325 4550);
FORCEPROP 2 LAST SIG_NAME M_D_CPU0_SA_CS_N<0>
J 0
(-8275 4560);
DISPLAY 0.489362 (-8275 4560);
WIRE 16 -1 (-7525 4400)(-8325 4400);
FORCEPROP 2 LAST SIG_NAME M_D_CPU0_SB_CS_N<0>
J 0
(-8275 4410);
DISPLAY 0.489362 (-8275 4410);
WIRE 16 -1 (-7525 4600)(-8325 4600);
FORCEPROP 2 LAST SIG_NAME M_D_CPU0_SA_CS_N<1>
J 0
(-8275 4610);
DISPLAY 0.489362 (-8275 4610);
WIRE 16 -1 (-7525 4450)(-8325 4450);
FORCEPROP 2 LAST SIG_NAME M_D_CPU0_SB_CS_N<1>
J 0
(-8275 4460);
DISPLAY 0.489362 (-8275 4460);
WIRE 16 -1 (-6125 5500)(-6325 5500);
WIRE 16 -1 (-6125 5400)(-6325 5400);
WIRE 16 -1 (-6325 5350)(-6125 5350);
WIRE 16 -1 (-6125 5250)(-6325 5250);
WIRE 16 -1 (-6125 5200)(-6325 5200);
WIRE 16 -1 (-6325 5150)(-6125 5150);
WIRE 16 -1 (-6125 5100)(-6325 5100);
WIRE 16 -1 (-6125 5050)(-6325 5050);
WIRE 16 -1 (-6125 5000)(-6325 5000);
WIRE 16 -1 (-6325 4950)(-6125 4950);
WIRE 16 -1 (-6125 4900)(-6325 4900);
WIRE 16 -1 (-6125 4850)(-6325 4850);
WIRE 16 -1 (-6125 4800)(-6325 4800);
WIRE 16 -1 (-6325 4750)(-6125 4750);
WIRE 16 -1 (-6125 4700)(-6325 4700);
WIRE 16 -1 (-6125 4650)(-6325 4650);
WIRE 16 -1 (-6325 4550)(-6125 4550);
WIRE 16 -1 (-6125 4500)(-6325 4500);
WIRE 16 -1 (-6125 4250)(-6325 4250);
WIRE 16 -1 (-6125 4200)(-6325 4200);
WIRE 16 -1 (-6325 4150)(-6125 4150);
WIRE 16 -1 (-6125 4100)(-6325 4100);
WIRE 16 -1 (-6125 4050)(-6325 4050);
WIRE 16 -1 (-6125 4000)(-6325 4000);
WIRE 16 -1 (-6325 3900)(-6125 3900);
WIRE 16 -1 (-6125 3850)(-6325 3850);
WIRE 16 -1 (-6125 3800)(-6325 3800);
WIRE 16 -1 (-6125 3750)(-6325 3750);
WIRE 16 -1 (-6325 3700)(-6125 3700);
WIRE 16 -1 (-6125 3650)(-6325 3650);
WIRE 16 -1 (-6125 3600)(-6325 3600);
WIRE 16 -1 (-6125 3550)(-6325 3550);
WIRE 16 -1 (-6325 3500)(-6125 3500);
WIRE 16 -1 (-6125 3450)(-6325 3450);
WIRE 16 -1 (-6125 3400)(-6325 3400);
WIRE 16 -1 (-6125 3350)(-6325 3350);
WIRE 16 -1 (-6325 3300)(-6125 3300);
WIRE 16 -1 (-6125 3250)(-6325 3250);
WIRE 16 -1 (-6125 3200)(-6325 3200);
WIRE 16 -1 (-6125 3150)(-6325 3150);
WIRE 16 -1 (-6325 3100)(-6125 3100);
WIRE 16 -1 (-6125 3050)(-6325 3050);
WIRE 16 -1 (-6125 3000)(-6325 3000);
WIRE 16 -1 (-6125 2950)(-6325 2950);
WIRE 16 -1 (-6325 2900)(-6125 2900);
WIRE 16 -1 (-6125 2850)(-6325 2850);
WIRE 16 -1 (-6125 2800)(-6325 2800);
WIRE 16 -1 (-6125 2750)(-6325 2750);
WIRE 16 -1 (-6325 2700)(-6125 2700);
WIRE 16 -1 (-6125 2650)(-6325 2650);
WIRE 16 -1 (-6125 2600)(-6325 2600);
WIRE 16 -1 (-6125 2550)(-6325 2550);
WIRE 16 -1 (-6325 2500)(-6125 2500);
WIRE 16 -1 (-6125 2450)(-6325 2450);
WIRE 16 -1 (-6125 2400)(-6325 2400);
WIRE 16 -1 (-6125 2350)(-6325 2350);
WIRE 16 -1 (-7525 2100)(-8325 2100);
FORCEPROP 2 LAST SIG_NAME M_D_CPU0_SB_RSP<0>
J 0
(-8275 2110);
DISPLAY 0.489362 (-8275 2110);
WIRE 16 -1 (-7525 4700)(-8325 4700);
FORCEPROP 2 LAST SIG_NAME M_D_CPU0_SB_PAR
J 0
(-8275 4710);
DISPLAY 0.489362 (-8275 4710);
WIRE 16 -1 (-6125 5300)(-6325 5300);
WIRE 16 -1 (-6325 5550)(-6125 5550);
WIRE 16 -1 (-7525 5550)(-7725 5550);
WIRE 16 -1 (-3900 4375)(-3550 4375);
WIRE 16 -1 (-3750 4325)(-3900 4325);
WIRE 16 -1 (-3900 3425)(-3550 3425);
WIRE 16 -1 (-3750 3375)(-3900 3375);
WIRE 16 -1 (-3750 3725)(-3900 3725);
WIRE 16 -1 (-3900 2625)(-3550 2625);
WIRE 16 -1 (-3750 2675)(-3900 2675);
WIRE 16 -1 (-3900 2725)(-3550 2725);
WIRE 16 -1 (-3900 2775)(-3750 2775);
WIRE 16 -1 (-3900 3875)(-3550 3875);
WIRE 16 -1 (-3750 3925)(-3900 3925);
WIRE 16 -1 (-3900 2825)(-3550 2825);
WIRE 16 -1 (-3750 2875)(-3900 2875);
WIRE 16 -1 (-3900 3975)(-3550 3975);
WIRE 16 -1 (-3750 4025)(-3900 4025);
WIRE 16 -1 (-3900 2925)(-3550 2925);
WIRE 16 -1 (-3750 2975)(-3900 2975);
WIRE 16 -1 (-3900 4075)(-3550 4075);
WIRE 16 -1 (-3750 4125)(-3900 4125);
WIRE 16 -1 (-3900 3025)(-3550 3025);
WIRE 16 -1 (-3750 3075)(-3900 3075);
WIRE 16 -1 (-3900 4175)(-3550 4175);
WIRE 16 -1 (-3900 4225)(-3750 4225);
WIRE 16 -1 (-3900 3125)(-3550 3125);
WIRE 16 -1 (-3900 3175)(-3750 3175);
WIRE 16 -1 (-3900 4275)(-3550 4275);
WIRE 16 -1 (-3900 3225)(-3550 3225);
WIRE 16 -1 (-3750 3275)(-3900 3275);
WIRE 16 -1 (-3750 4425)(-3900 4425);
WIRE 16 -1 (-3900 3325)(-3550 3325);
WIRE 16 -1 (-3900 4475)(-3550 4475);
WIRE 16 -1 (-3750 4525)(-3900 4525);
WIRE 16 -1 (-3900 4625)(-3750 4625);
WIRE 16 -1 (-3900 3825)(-3750 3825);
WIRE 16 -1 (-3900 3775)(-3550 3775);
WIRE 16 -1 (-3900 3675)(-3550 3675);
WIRE 16 -1 (-3900 3575)(-3750 3575);
WIRE 16 -1 (-3900 3525)(-3550 3525);
WIRE 16 -1 (-3750 3475)(-3900 3475);
WIRE 16 -1 (-3900 4575)(-3550 4575);
WIRE 16 -1 (-6125 4300)(-6325 4300);
WIRE 16 -1 (-6325 4350)(-6125 4350);
WIRE 16 -1 (-6125 4400)(-6325 4400);
WIRE 16 -1 (-6125 4450)(-6325 4450);
WIRE 16 -1 (-6125 4600)(-6325 4600);
WIRE 16 -1 (-6125 5450)(-6325 5450);
WIRE 16 -1 (-7525 4750)(-8325 4750);
FORCEPROP 2 LAST SIG_NAME M_D_CPU0_SA_PAR
J 0
(-8275 4760);
DISPLAY 0.489362 (-8275 4760);
WIRE 16 -1 (-7525 2150)(-8325 2150);
FORCEPROP 2 LAST SIG_NAME M_D_CPU0_SA_RSP<0>
J 0
(-8275 2160);
DISPLAY 0.489362 (-8275 2160);
WIRE 16 -1 (-8175 2300)(-8175 2700);
WIRE 16 -1 (-8175 2300)(-8375 2300);
WIRE 16 -1 (-7525 2700)(-8175 2700);
FORCEPROP 2 LAST SIG_NAME PWRGD_CHD_CPU0_DIMM
J 0
(-8100 2710);
DISPLAY 0.489362 (-8100 2710);
FORCEPROP 2 LASTPROP $XRERR UNIQUE?
J 0
(-8340 2710);
DISPLAY 0.638298 (-8340 2710);
PAINT MONO (-8340 2710);
DISPLAY INVISIBLE (-8340 2710);
WIRE 16 -1 (-8375 2350)(-8375 2300);
WIRE 16 -1 (-8375 2300)(-8400 2300);
WIRE 16 -1 (-8950 2300)(-8600 2300);
FORCEPROP 2 LAST SIG_NAME PWRGD_CHAF_CPU0
J 0
(-8935 2310);
DISPLAY 0.489362 (-8935 2310);
WIRE 16 -1 (-8300 2900)(-8300 3000);
WIRE 16 -1 (-8300 2900)(-8800 2900);
FORCEPROP 2 LAST SIG_NAME I3C_SPD_DDRAF_CPU0_SDA
J 0
(-8810 2910);
DISPLAY 0.489362 (-8810 2910);
WIRE 16 -1 (-8300 3000)(-8275 3000);
WIRE 16 -1 (-7525 3200)(-8050 3200);
FORCEPROP 2 LAST SIG_NAME M_D_CPU0_ALERT_N
J 0
(-8035 3210);
DISPLAY 0.489362 (-8035 3210);
WIRE 16 -1 (-7525 3000)(-8075 3000);
FORCEPROP 2 LAST SIG_NAME I3C_SPD_DDRD_CPU0_SDA
J 0
(-7960 3010);
DISPLAY 0.361702 (-7960 3010);
FORCEPROP 2 LASTPROP $XRERR UNIQUE?
J 0
(-8200 3010);
DISPLAY 0.638298 (-8200 3010);
PAINT MONO (-8200 3010);
DISPLAY INVISIBLE (-8200 3010);
WIRE 16 -1 (-7525 3050)(-8325 3050);
FORCEPROP 2 LAST SIG_NAME PD_CHD_CPU0_DIMM_SAA
J 0
(-8300 3060);
DISPLAY 0.489362 (-8300 3060);
WIRE 16 -1 (-8600 3475)(-8600 3525);
WIRE 16 -1 (-8600 3525)(-8475 3525);
WIRE 16 -1 (-8475 3525)(-8475 3100);
WIRE 16 -1 (-8475 3525)(-8475 3575);
WIRE 16 -1 (-8475 3100)(-7525 3100);
DOT 1 (-2375 5775);
DOT 1 (-2950 5775);
DOT 1 (-2950 5350);
DOT 1 (-2250 5350);
DOT 1 (-2250 4600);
DOT 1 (-8375 2300);
DOT 1 (-8475 3525);
DOT 1 (-2250 2100);
DOT 1 (-2250 2150);
DOT 1 (-2250 2200);
DOT 1 (-2250 2250);
DOT 1 (-2250 2300);
DOT 1 (-2250 2350);
DOT 1 (-2250 2400);
DOT 1 (-2250 2450);
DOT 1 (-2250 2500);
DOT 1 (-2250 2550);
DOT 1 (-2250 2600);
DOT 1 (-2250 2700);
DOT 1 (-2250 2650);
DOT 1 (-2250 2750);
DOT 1 (-2250 2800);
DOT 1 (-2250 2850);
DOT 1 (-2250 2900);
DOT 1 (-2250 2950);
DOT 1 (-2250 3000);
DOT 1 (-2250 3050);
DOT 1 (-2250 3100);
DOT 1 (-2250 3200);
DOT 1 (-2250 3150);
DOT 1 (-2250 3250);
DOT 1 (-2250 3300);
DOT 1 (-2250 3350);
DOT 1 (-2250 3400);
DOT 1 (-2250 3450);
DOT 1 (-2250 3500);
DOT 1 (-2250 3550);
DOT 1 (-2250 3600);
DOT 1 (-2250 3650);
DOT 1 (-2250 3700);
DOT 1 (-2250 3750);
DOT 1 (-2250 3800);
DOT 1 (-2250 3850);
DOT 1 (-2250 3900);
DOT 1 (-2250 3950);
DOT 1 (-2250 4000);
DOT 1 (-2250 4050);
DOT 1 (-2250 4100);
DOT 1 (-450 2050);
DOT 1 (-450 2000);
DOT 1 (-450 2100);
DOT 1 (-450 2200);
DOT 1 (-450 2250);
DOT 1 (-450 2300);
DOT 1 (-450 2350);
DOT 1 (-450 2450);
DOT 1 (-450 2400);
DOT 1 (-450 2500);
DOT 1 (-450 2550);
DOT 1 (-450 2600);
DOT 1 (-450 2700);
DOT 1 (-450 2650);
DOT 1 (-450 2750);
DOT 1 (-450 2800);
DOT 1 (-450 2850);
DOT 1 (-450 2950);
DOT 1 (-450 2900);
DOT 1 (-450 3000);
DOT 1 (-450 3050);
DOT 1 (-450 3100);
DOT 1 (-450 3150);
DOT 1 (-450 3250);
DOT 1 (-450 3200);
DOT 1 (-450 3350);
DOT 1 (-450 3300);
DOT 1 (-450 3400);
DOT 1 (-450 3450);
DOT 1 (-450 3500);
DOT 1 (-450 3600);
DOT 1 (-450 3550);
DOT 1 (-450 3650);
DOT 1 (-450 3700);
DOT 1 (-450 3750);
DOT 1 (-450 3850);
DOT 1 (-450 3800);
DOT 1 (-450 3900);
DOT 1 (-450 3950);
DOT 1 (-450 4000);
DOT 1 (-450 4150);
DOT 1 (-2250 4150);
DOT 1 (-2250 4200);
DOT 1 (-2250 4250);
DOT 1 (-2250 4300);
DOT 1 (-2250 4350);
DOT 1 (-2250 4450);
DOT 1 (-2250 4500);
DOT 1 (-2250 4900);
DOT 1 (-2250 5000);
DOT 1 (-2250 5100);
DOT 1 (-2250 5150);
DOT 1 (-2250 5300);
DOT 1 (-450 4200);
DOT 1 (-450 4250);
DOT 1 (-450 4300);
DOT 1 (-450 4350);
DOT 1 (-450 4400);
DOT 1 (-450 4500);
DOT 1 (-450 4450);
DOT 1 (-450 4550);
DOT 1 (-450 4600);
DOT 1 (-450 4650);
DOT 1 (-450 4750);
DOT 1 (-450 4700);
DOT 1 (-450 4800);
DOT 1 (-450 4850);
DOT 1 (-450 4900);
DOT 1 (-450 5000);
DOT 1 (-450 4950);
DOT 1 (-450 5050);
DOT 1 (-450 5100);
DOT 1 (-450 5150);
DOT 1 (-450 5200);
DOT 1 (-450 5250);
DOT 1 (-450 5300);
DOT 1 (-2250 4400);
DOT 1 (-450 4100);
DOT 1 (-450 4050);
DOT 1 (-2250 5050);
DOT 1 (-2250 4950);
DOT 1 (-2250 4850);
DOT 1 (-2250 4800);
DOT 1 (-2250 4700);
DOT 1 (-2250 4550);
DOT 1 (-2250 4650);
DOT 1 (-2250 4750);
QUIT
